FILE_TYPE = MACRO_DRAWING;
SET COLOR_WIRE YELLOW;
SET COLOR_PROP ORANGE;
SET COLOR_DOT WHITE;
SET COLOR_ARC YELLOW;
SET COLOR_BODY GREEN;
SET COLOR_NOTE PURPLE;
SET PROP_DISPLAY VALUE;
SET PAGE_NUMBER P61;
FORCEADD TAP..1
R 2
(-200 -525);
FORCEPROP 3 LASTPIN (-150 -525) SIG_NAME P5E_CPU1_PE3_RX_DN<0>
J 0
(-140 -515);
DISPLAY 0.659574 (-140 -515);
PAINT MONO (-140 -515);
DISPLAY INVISIBLE (-140 -515);
FORCEPROP 1 LASTPIN (-150 -525) BN 0
J 2
(-138 -517);
DISPLAY 0.680851 (-138 -517);
PAINT GREEN (-138 -517);
FORCEPROP 2 LAST CDS_LIB standard
J 0
(-200 -525);
DISPLAY INVISIBLE (-200 -525);
FORCEPROP 1 LAST BODY_TYPE PLUMBING
J 2
(-200 -475);
DISPLAY 0.872340 (-200 -475);
PAINT GREEN (-200 -475);
DISPLAY INVISIBLE (-200 -475);
FORCEPROP 1 LAST HDL_TAP TRUE
J 2
(-525 -650);
DISPLAY 0.872340 (-525 -650);
DISPLAY INVISIBLE (-525 -650);
FORCEPROP 1 LAST PATH I1
J 2
(-198 -525);
DISPLAY 0.872340 (-198 -525);
PAINT GREEN (-198 -525);
DISPLAY INVISIBLE (-198 -525);
FORCEADD TAP..1
R 2
(-200 -25);
FORCEPROP 3 LASTPIN (-150 -25) SIG_NAME P5E_CPU1_PE3_RX_DN<10>
J 0
(-140 -15);
DISPLAY 0.659574 (-140 -15);
PAINT MONO (-140 -15);
DISPLAY INVISIBLE (-140 -15);
FORCEPROP 1 LASTPIN (-150 -25) BN 10
J 2
(-138 -17);
DISPLAY 0.680851 (-138 -17);
PAINT GREEN (-138 -17);
FORCEPROP 2 LAST CDS_LIB standard
J 0
(-200 -25);
DISPLAY INVISIBLE (-200 -25);
FORCEPROP 1 LAST BODY_TYPE PLUMBING
J 2
(-200 25);
DISPLAY 0.872340 (-200 25);
PAINT GREEN (-200 25);
DISPLAY INVISIBLE (-200 25);
FORCEPROP 1 LAST HDL_TAP TRUE
J 2
(-525 -150);
DISPLAY 0.872340 (-525 -150);
DISPLAY INVISIBLE (-525 -150);
FORCEPROP 1 LAST PATH I10
J 2
(-198 -25);
DISPLAY 0.872340 (-198 -25);
PAINT GREEN (-198 -25);
DISPLAY INVISIBLE (-198 -25);
FORCEADD TAP..1
(3175 1025);
FORCEPROP 3 LASTPIN (3125 1025) SIG_NAME P5E_CPU1_PE3_TX_DP<14>
J 0
(3135 1035);
DISPLAY 0.659574 (3135 1035);
PAINT MONO (3135 1035);
DISPLAY INVISIBLE (3135 1035);
FORCEPROP 1 LASTPIN (3125 1025) BN 14
J 0
(3113 1033);
DISPLAY 0.680851 (3113 1033);
PAINT GREEN (3113 1033);
FORCEPROP 2 LAST CDS_LIB standard
J 0
(3175 1025);
DISPLAY INVISIBLE (3175 1025);
FORCEPROP 1 LAST BODY_TYPE PLUMBING
J 0
(3175 1075);
DISPLAY 0.872340 (3175 1075);
PAINT GREEN (3175 1075);
DISPLAY INVISIBLE (3175 1075);
FORCEPROP 1 LAST HDL_TAP TRUE
J 0
(3500 900);
DISPLAY 0.872340 (3500 900);
DISPLAY INVISIBLE (3500 900);
FORCEPROP 1 LAST PATH I100
J 0
(3173 1025);
DISPLAY 0.872340 (3173 1025);
PAINT GREEN (3173 1025);
DISPLAY INVISIBLE (3173 1025);
FORCEADD TAP..1
(3175 925);
FORCEPROP 3 LASTPIN (3125 925) SIG_NAME P5E_CPU1_PE3_TX_DP<12>
J 0
(3135 935);
DISPLAY 0.659574 (3135 935);
PAINT MONO (3135 935);
DISPLAY INVISIBLE (3135 935);
FORCEPROP 1 LASTPIN (3125 925) BN 12
J 0
(3113 933);
DISPLAY 0.680851 (3113 933);
PAINT GREEN (3113 933);
FORCEPROP 2 LAST CDS_LIB standard
J 0
(3175 925);
DISPLAY INVISIBLE (3175 925);
FORCEPROP 1 LAST BODY_TYPE PLUMBING
J 0
(3175 975);
DISPLAY 0.872340 (3175 975);
PAINT GREEN (3175 975);
DISPLAY INVISIBLE (3175 975);
FORCEPROP 1 LAST HDL_TAP TRUE
J 0
(3500 800);
DISPLAY 0.872340 (3500 800);
DISPLAY INVISIBLE (3500 800);
FORCEPROP 1 LAST PATH I101
J 0
(3173 925);
DISPLAY 0.872340 (3173 925);
PAINT GREEN (3173 925);
DISPLAY INVISIBLE (3173 925);
FORCEADD TAP..1
(3175 1075);
FORCEPROP 3 LASTPIN (3125 1075) SIG_NAME P5E_CPU1_PE3_TX_DP<15>
J 0
(3135 1085);
DISPLAY 0.659574 (3135 1085);
PAINT MONO (3135 1085);
DISPLAY INVISIBLE (3135 1085);
FORCEPROP 1 LASTPIN (3125 1075) BN 15
J 0
(3113 1083);
DISPLAY 0.680851 (3113 1083);
PAINT GREEN (3113 1083);
FORCEPROP 2 LAST CDS_LIB standard
J 0
(3175 1075);
DISPLAY INVISIBLE (3175 1075);
FORCEPROP 1 LAST BODY_TYPE PLUMBING
J 0
(3175 1125);
DISPLAY 0.872340 (3175 1125);
PAINT GREEN (3175 1125);
DISPLAY INVISIBLE (3175 1125);
FORCEPROP 1 LAST HDL_TAP TRUE
J 0
(3500 950);
DISPLAY 0.872340 (3500 950);
DISPLAY INVISIBLE (3500 950);
FORCEPROP 1 LAST PATH I102
J 0
(3173 1075);
DISPLAY 0.872340 (3173 1075);
PAINT GREEN (3173 1075);
DISPLAY INVISIBLE (3173 1075);
FORCEADD OFFPAGE..2
(4275 250);
FORCEPROP 2 LAST $XR0 177 
J 0
(4464 250);
DISPLAY 0.638298 (4464 250);
PAINT MONO (4464 250);
FORCEPROP 2 LAST CDS_LIB standard
J 0
(4275 250);
PAINT MONO (4275 250);
DISPLAY INVISIBLE (4275 250);
FORCEPROP 1 LAST OFFPAGE TRUE
J 0
(4600 125);
DISPLAY 1.170213 (4600 125);
PAINT GREEN (4600 125);
DISPLAY INVISIBLE (4600 125);
FORCEPROP 1 LAST COMMENT_BODY TRUE
J 0
(4230 155);
DISPLAY 1.170213 (4230 155);
PAINT GREEN (4230 155);
DISPLAY INVISIBLE (4230 155);
FORCEPROP 2 LAST PATH I103
J 0
(4450 325);
DISPLAY 1.021277 (4450 325);
DISPLAY INVISIBLE (4450 325);
FORCEADD OFFPAGE..2
(4275 1100);
FORCEPROP 2 LAST $XR0 177 
J 0
(4464 1100);
DISPLAY 0.638298 (4464 1100);
PAINT MONO (4464 1100);
FORCEPROP 2 LAST CDS_LIB standard
J 0
(4275 1100);
PAINT MONO (4275 1100);
DISPLAY INVISIBLE (4275 1100);
FORCEPROP 1 LAST OFFPAGE TRUE
J 0
(4600 975);
DISPLAY 1.170213 (4600 975);
PAINT GREEN (4600 975);
DISPLAY INVISIBLE (4600 975);
FORCEPROP 1 LAST COMMENT_BODY TRUE
J 0
(4230 1005);
DISPLAY 1.170213 (4230 1005);
PAINT GREEN (4230 1005);
DISPLAY INVISIBLE (4230 1005);
FORCEPROP 2 LAST PATH I104
J 0
(4450 1175);
DISPLAY 1.021277 (4450 1175);
DISPLAY INVISIBLE (4450 1175);
FORCEADD TAP..1
R 2
(-200 -125);
FORCEPROP 3 LASTPIN (-150 -125) SIG_NAME P5E_CPU1_PE3_RX_DN<8>
J 0
(-140 -115);
DISPLAY 0.659574 (-140 -115);
PAINT MONO (-140 -115);
DISPLAY INVISIBLE (-140 -115);
FORCEPROP 1 LASTPIN (-150 -125) BN 8
J 2
(-138 -117);
DISPLAY 0.680851 (-138 -117);
PAINT GREEN (-138 -117);
FORCEPROP 2 LAST CDS_LIB standard
J 0
(-200 -125);
DISPLAY INVISIBLE (-200 -125);
FORCEPROP 1 LAST BODY_TYPE PLUMBING
J 2
(-200 -75);
DISPLAY 0.872340 (-200 -75);
PAINT GREEN (-200 -75);
DISPLAY INVISIBLE (-200 -75);
FORCEPROP 1 LAST HDL_TAP TRUE
J 2
(-525 -250);
DISPLAY 0.872340 (-525 -250);
DISPLAY INVISIBLE (-525 -250);
FORCEPROP 1 LAST PATH I11
J 2
(-198 -125);
DISPLAY 0.872340 (-198 -125);
PAINT GREEN (-198 -125);
DISPLAY INVISIBLE (-198 -125);
FORCEADD SOCKET4677_AZIF0045P001C01CS..20
(1500 275);
FORCEPROP 1 LAST PART_NUMBER DGA^7000023
J 0
(450 1325);
DISPLAY 0.723404 (450 1325);
PAINT GREEN (450 1325);
DISPLAY INVISIBLE (450 1325);
FORCEPROP 2 LAST VALUE SOCKET4677_AZIF0045-P001C01CS
J 0
(450 1450);
DISPLAY 1.021277 (450 1450);
FORCEPROP 1 LAST MATERIAL IO
J 0
(450 1250);
DISPLAY 0.723404 (450 1250);
PAINT GREEN (450 1250);
FORCEPROP 2 LAST PART_TYPE SMLF
J 0
(450 1500);
DISPLAY 1.021277 (450 1500);
FORCEPROP 1 LAST $LOCATION U1
J 0
(450 1400);
DISPLAY 0.723404 (450 1400);
PAINT GREEN (450 1400);
FORCEPROP 0 LASTPIN (300 -525) $PN EH89
J 2
(290 -515);
DISPLAY 0.680851 (290 -515);
PAINT MONO (290 -515);
FORCEPROP 0 LASTPIN (300 -475) $PN ED91
J 2
(290 -465);
DISPLAY 0.680851 (290 -465);
PAINT MONO (290 -465);
FORCEPROP 0 LASTPIN (300 -425) $PN EC90
J 2
(290 -415);
DISPLAY 0.680851 (290 -415);
PAINT MONO (290 -415);
FORCEPROP 0 LASTPIN (300 -375) $PN DY91
J 2
(290 -365);
DISPLAY 0.680851 (290 -365);
PAINT MONO (290 -365);
FORCEPROP 0 LASTPIN (300 -325) $PN DV89
J 2
(290 -315);
DISPLAY 0.680851 (290 -315);
PAINT MONO (290 -315);
FORCEPROP 0 LASTPIN (300 -275) $PN DU90
J 2
(290 -265);
DISPLAY 0.680851 (290 -265);
PAINT MONO (290 -265);
FORCEPROP 0 LASTPIN (300 -225) $PN DP89
J 2
(290 -215);
DISPLAY 0.680851 (290 -215);
PAINT MONO (290 -215);
FORCEPROP 0 LASTPIN (300 -175) $PN DN90
J 2
(290 -165);
DISPLAY 0.680851 (290 -165);
PAINT MONO (290 -165);
FORCEPROP 0 LASTPIN (300 -125) $PN DL90
J 2
(290 -115);
DISPLAY 0.680851 (290 -115);
PAINT MONO (290 -115);
FORCEPROP 0 LASTPIN (300 -75) $PN DH91
J 2
(290 -65);
DISPLAY 0.680851 (290 -65);
PAINT MONO (290 -65);
FORCEPROP 0 LASTPIN (300 -25) $PN DG90
J 2
(290 -15);
DISPLAY 0.680851 (290 -15);
PAINT MONO (290 -15);
FORCEPROP 0 LASTPIN (300 25) $PN DD91
J 2
(290 35);
DISPLAY 0.680851 (290 35);
PAINT MONO (290 35);
FORCEPROP 0 LASTPIN (300 75) $PN DB89
J 2
(290 85);
DISPLAY 0.680851 (290 85);
PAINT MONO (290 85);
FORCEPROP 0 LASTPIN (300 125) $PN DA90
J 2
(290 135);
DISPLAY 0.680851 (290 135);
PAINT MONO (290 135);
FORCEPROP 0 LASTPIN (300 175) $PN CV89
J 2
(290 185);
DISPLAY 0.680851 (290 185);
PAINT MONO (290 185);
FORCEPROP 0 LASTPIN (300 225) $PN CU90
J 2
(290 235);
DISPLAY 0.680851 (290 235);
PAINT MONO (290 235);
FORCEPROP 0 LASTPIN (300 325) $PN EJ90
J 2
(290 335);
DISPLAY 0.680851 (290 335);
PAINT MONO (290 335);
FORCEPROP 0 LASTPIN (300 375) $PN EE90
J 2
(290 385);
DISPLAY 0.680851 (290 385);
PAINT MONO (290 385);
FORCEPROP 0 LASTPIN (300 425) $PN EB89
J 2
(290 435);
DISPLAY 0.680851 (290 435);
PAINT MONO (290 435);
FORCEPROP 0 LASTPIN (300 475) $PN EA90
J 2
(290 485);
DISPLAY 0.680851 (290 485);
PAINT MONO (290 485);
FORCEPROP 0 LASTPIN (300 525) $PN DW90
J 2
(290 535);
DISPLAY 0.680851 (290 535);
PAINT MONO (290 535);
FORCEPROP 0 LASTPIN (300 575) $PN DT91
J 2
(290 585);
DISPLAY 0.680851 (290 585);
PAINT MONO (290 585);
FORCEPROP 0 LASTPIN (300 625) $PN DR90
J 2
(290 635);
DISPLAY 0.680851 (290 635);
PAINT MONO (290 635);
FORCEPROP 0 LASTPIN (300 675) $PN DM91
J 2
(290 685);
DISPLAY 0.680851 (290 685);
PAINT MONO (290 685);
FORCEPROP 0 LASTPIN (300 725) $PN DK89
J 2
(290 735);
DISPLAY 0.680851 (290 735);
PAINT MONO (290 735);
FORCEPROP 0 LASTPIN (300 775) $PN DJ90
J 2
(290 785);
DISPLAY 0.680851 (290 785);
PAINT MONO (290 785);
FORCEPROP 0 LASTPIN (300 825) $PN DF89
J 2
(290 835);
DISPLAY 0.680851 (290 835);
PAINT MONO (290 835);
FORCEPROP 0 LASTPIN (300 875) $PN DE90
J 2
(290 885);
DISPLAY 0.680851 (290 885);
PAINT MONO (290 885);
FORCEPROP 0 LASTPIN (300 925) $PN DC90
J 2
(290 935);
DISPLAY 0.680851 (290 935);
PAINT MONO (290 935);
FORCEPROP 0 LASTPIN (300 975) $PN CY91
J 2
(290 985);
DISPLAY 0.680851 (290 985);
PAINT MONO (290 985);
FORCEPROP 0 LASTPIN (300 1025) $PN CW90
J 2
(290 1035);
DISPLAY 0.680851 (290 1035);
PAINT MONO (290 1035);
FORCEPROP 0 LASTPIN (300 1075) $PN CT91
J 2
(290 1085);
DISPLAY 0.680851 (290 1085);
PAINT MONO (290 1085);
FORCEPROP 0 LASTPIN (2700 -525) $PN EE86
J 0
(2710 -515);
DISPLAY 0.680851 (2710 -515);
PAINT MONO (2710 -515);
FORCEPROP 0 LASTPIN (2700 -475) $PN EB85
J 0
(2710 -465);
DISPLAY 0.680851 (2710 -465);
PAINT MONO (2710 -465);
FORCEPROP 0 LASTPIN (2700 -425) $PN DY87
J 0
(2710 -415);
DISPLAY 0.680851 (2710 -415);
PAINT MONO (2710 -415);
FORCEPROP 0 LASTPIN (2700 -375) $PN DV85
J 0
(2710 -365);
DISPLAY 0.680851 (2710 -365);
PAINT MONO (2710 -365);
FORCEPROP 0 LASTPIN (2700 -325) $PN DT87
J 0
(2710 -315);
DISPLAY 0.680851 (2710 -315);
PAINT MONO (2710 -315);
FORCEPROP 0 LASTPIN (2700 -275) $PN DP85
J 0
(2710 -265);
DISPLAY 0.680851 (2710 -265);
PAINT MONO (2710 -265);
FORCEPROP 0 LASTPIN (2700 -225) $PN DM87
J 0
(2710 -215);
DISPLAY 0.680851 (2710 -215);
PAINT MONO (2710 -215);
FORCEPROP 0 LASTPIN (2700 -175) $PN DK85
J 0
(2710 -165);
DISPLAY 0.680851 (2710 -165);
PAINT MONO (2710 -165);
FORCEPROP 0 LASTPIN (2700 -125) $PN DH87
J 0
(2710 -115);
DISPLAY 0.680851 (2710 -115);
PAINT MONO (2710 -115);
FORCEPROP 0 LASTPIN (2700 -75) $PN DF85
J 0
(2710 -65);
DISPLAY 0.680851 (2710 -65);
PAINT MONO (2710 -65);
FORCEPROP 0 LASTPIN (2700 -25) $PN DD87
J 0
(2710 -15);
DISPLAY 0.680851 (2710 -15);
PAINT MONO (2710 -15);
FORCEPROP 0 LASTPIN (2700 25) $PN DB85
J 0
(2710 35);
DISPLAY 0.680851 (2710 35);
PAINT MONO (2710 35);
FORCEPROP 0 LASTPIN (2700 75) $PN CY87
J 0
(2710 85);
DISPLAY 0.680851 (2710 85);
PAINT MONO (2710 85);
FORCEPROP 0 LASTPIN (2700 125) $PN CV85
J 0
(2710 135);
DISPLAY 0.680851 (2710 135);
PAINT MONO (2710 135);
FORCEPROP 0 LASTPIN (2700 175) $PN CT87
J 0
(2710 185);
DISPLAY 0.680851 (2710 185);
PAINT MONO (2710 185);
FORCEPROP 0 LASTPIN (2700 225) $PN CP85
J 0
(2710 235);
DISPLAY 0.680851 (2710 235);
PAINT MONO (2710 235);
FORCEPROP 0 LASTPIN (2700 325) $PN ED87
J 0
(2710 335);
DISPLAY 0.680851 (2710 335);
PAINT MONO (2710 335);
FORCEPROP 0 LASTPIN (2700 375) $PN EC86
J 0
(2710 385);
DISPLAY 0.680851 (2710 385);
PAINT MONO (2710 385);
FORCEPROP 0 LASTPIN (2700 425) $PN EA86
J 0
(2710 435);
DISPLAY 0.680851 (2710 435);
PAINT MONO (2710 435);
FORCEPROP 0 LASTPIN (2700 475) $PN DW86
J 0
(2710 485);
DISPLAY 0.680851 (2710 485);
PAINT MONO (2710 485);
FORCEPROP 0 LASTPIN (2700 525) $PN DU86
J 0
(2710 535);
DISPLAY 0.680851 (2710 535);
PAINT MONO (2710 535);
FORCEPROP 0 LASTPIN (2700 575) $PN DR86
J 0
(2710 585);
DISPLAY 0.680851 (2710 585);
PAINT MONO (2710 585);
FORCEPROP 0 LASTPIN (2700 625) $PN DN86
J 0
(2710 635);
DISPLAY 0.680851 (2710 635);
PAINT MONO (2710 635);
FORCEPROP 0 LASTPIN (2700 675) $PN DL86
J 0
(2710 685);
DISPLAY 0.680851 (2710 685);
PAINT MONO (2710 685);
FORCEPROP 0 LASTPIN (2700 725) $PN DJ86
J 0
(2710 735);
DISPLAY 0.680851 (2710 735);
PAINT MONO (2710 735);
FORCEPROP 0 LASTPIN (2700 775) $PN DG86
J 0
(2710 785);
DISPLAY 0.680851 (2710 785);
PAINT MONO (2710 785);
FORCEPROP 0 LASTPIN (2700 825) $PN DE86
J 0
(2710 835);
DISPLAY 0.680851 (2710 835);
PAINT MONO (2710 835);
FORCEPROP 0 LASTPIN (2700 875) $PN DC86
J 0
(2710 885);
DISPLAY 0.680851 (2710 885);
PAINT MONO (2710 885);
FORCEPROP 0 LASTPIN (2700 925) $PN DA86
J 0
(2710 935);
DISPLAY 0.680851 (2710 935);
PAINT MONO (2710 935);
FORCEPROP 0 LASTPIN (2700 975) $PN CW86
J 0
(2710 985);
DISPLAY 0.680851 (2710 985);
PAINT MONO (2710 985);
FORCEPROP 0 LASTPIN (2700 1025) $PN CU86
J 0
(2710 1035);
DISPLAY 0.680851 (2710 1035);
PAINT MONO (2710 1035);
FORCEPROP 0 LASTPIN (2700 1075) $PN CR86
J 0
(2710 1085);
DISPLAY 0.680851 (2710 1085);
PAINT MONO (2710 1085);
FORCEPROP 1 LAST CDS_LMAN_SYM_OUTLINE -1050,950,1050,-950
J 0
(1500 275);
DISPLAY 0.468085 (1500 275);
PAINT GREEN (1500 275);
DISPLAY INVISIBLE (1500 275);
FORCEPROP 1 LAST NEEDS_NO_SIZE TRUE
J 0
(1500 275);
DISPLAY 0.723404 (1500 275);
PAINT GREEN (1500 275);
DISPLAY INVISIBLE (1500 275);
FORCEPROP 2 LAST CDS_LIB pure_quanta
J 0
(1500 275);
DISPLAY INVISIBLE (1500 275);
FORCEPROP 2 LAST CDS_LOCATION U1
J 0
(450 1550);
DISPLAY 1.021277 (450 1550);
DISPLAY INVISIBLE (450 1550);
FORCEPROP 0 LAST $SEC 20
J 0
(450 1550);
DISPLAY 0.680851 (450 1550);
PAINT MONO (450 1550);
DISPLAY INVISIBLE (450 1550);
FORCEPROP 2 LAST CDS_SEC 20
J 0
(450 1550);
DISPLAY 1.021277 (450 1550);
DISPLAY INVISIBLE (450 1550);
FORCEPROP 1 LAST PATH I12
J 0
(1500 275);
DISPLAY 0.723404 (1500 275);
PAINT GREEN (1500 275);
DISPLAY INVISIBLE (1500 275);
FORCEADD TAP..1
R 2
(-200 25);
FORCEPROP 3 LASTPIN (-150 25) SIG_NAME P5E_CPU1_PE3_RX_DN<11>
J 0
(-140 35);
DISPLAY 0.659574 (-140 35);
PAINT MONO (-140 35);
DISPLAY INVISIBLE (-140 35);
FORCEPROP 1 LASTPIN (-150 25) BN 11
J 2
(-138 33);
DISPLAY 0.680851 (-138 33);
PAINT GREEN (-138 33);
FORCEPROP 2 LAST CDS_LIB standard
J 0
(-200 25);
DISPLAY INVISIBLE (-200 25);
FORCEPROP 1 LAST BODY_TYPE PLUMBING
J 2
(-200 75);
DISPLAY 0.872340 (-200 75);
PAINT GREEN (-200 75);
DISPLAY INVISIBLE (-200 75);
FORCEPROP 1 LAST HDL_TAP TRUE
J 2
(-525 -100);
DISPLAY 0.872340 (-525 -100);
DISPLAY INVISIBLE (-525 -100);
FORCEPROP 1 LAST PATH I13
J 2
(-198 25);
DISPLAY 0.872340 (-198 25);
PAINT GREEN (-198 25);
DISPLAY INVISIBLE (-198 25);
FORCEADD OFFPAGE..1
(-1450 250);
FORCEPROP 2 LAST $XR1 141 
J 0
(-1822 250);
DISPLAY 0.638298 (-1822 250);
PAINT MONO (-1822 250);
FORCEPROP 2 LAST $XR0 140 
J 0
(-1702 250);
DISPLAY 0.638298 (-1702 250);
PAINT MONO (-1702 250);
FORCEPROP 2 LAST CDS_LIB standard
J 0
(-1450 250);
PAINT MONO (-1450 250);
DISPLAY INVISIBLE (-1450 250);
FORCEPROP 1 LAST OFFPAGE TRUE
J 0
(-1125 125);
DISPLAY 0.872340 (-1125 125);
DISPLAY INVISIBLE (-1125 125);
FORCEPROP 1 LAST COMMENT_BODY TRUE
J 0
(-1325 150);
DISPLAY 0.872340 (-1325 150);
PAINT GREEN (-1325 150);
DISPLAY INVISIBLE (-1325 150);
FORCEPROP 2 LAST PATH I14
J 0
(-1400 325);
DISPLAY 1.021277 (-1400 325);
DISPLAY INVISIBLE (-1400 325);
FORCEADD OFFPAGE..1
(-1450 1100);
FORCEPROP 2 LAST $XR1 141 
J 0
(-1822 1100);
DISPLAY 0.638298 (-1822 1100);
PAINT MONO (-1822 1100);
FORCEPROP 2 LAST $XR0 140 
J 0
(-1702 1100);
DISPLAY 0.638298 (-1702 1100);
PAINT MONO (-1702 1100);
FORCEPROP 2 LAST CDS_LIB standard
J 0
(-1450 1100);
PAINT MONO (-1450 1100);
DISPLAY INVISIBLE (-1450 1100);
FORCEPROP 1 LAST OFFPAGE TRUE
J 0
(-1125 975);
DISPLAY 0.872340 (-1125 975);
DISPLAY INVISIBLE (-1125 975);
FORCEPROP 1 LAST COMMENT_BODY TRUE
J 0
(-1325 1000);
DISPLAY 0.872340 (-1325 1000);
PAINT GREEN (-1325 1000);
DISPLAY INVISIBLE (-1325 1000);
FORCEPROP 2 LAST PATH I15
J 0
(-1400 1175);
DISPLAY 1.021277 (-1400 1175);
DISPLAY INVISIBLE (-1400 1175);
FORCEADD TAP..1
R 2
(-200 75);
FORCEPROP 3 LASTPIN (-150 75) SIG_NAME P5E_CPU1_PE3_RX_DN<12>
J 0
(-140 85);
DISPLAY 0.659574 (-140 85);
PAINT MONO (-140 85);
DISPLAY INVISIBLE (-140 85);
FORCEPROP 1 LASTPIN (-150 75) BN 12
J 2
(-138 83);
DISPLAY 0.680851 (-138 83);
PAINT GREEN (-138 83);
FORCEPROP 2 LAST CDS_LIB standard
J 0
(-200 75);
DISPLAY INVISIBLE (-200 75);
FORCEPROP 1 LAST BODY_TYPE PLUMBING
J 2
(-200 125);
DISPLAY 0.872340 (-200 125);
PAINT GREEN (-200 125);
DISPLAY INVISIBLE (-200 125);
FORCEPROP 1 LAST HDL_TAP TRUE
J 2
(-525 -50);
DISPLAY 0.872340 (-525 -50);
DISPLAY INVISIBLE (-525 -50);
FORCEPROP 1 LAST PATH I16
J 2
(-198 75);
DISPLAY 0.872340 (-198 75);
PAINT GREEN (-198 75);
DISPLAY INVISIBLE (-198 75);
FORCEADD TAP..1
R 2
(-200 125);
FORCEPROP 3 LASTPIN (-150 125) SIG_NAME P5E_CPU1_PE3_RX_DN<13>
J 0
(-140 135);
DISPLAY 0.659574 (-140 135);
PAINT MONO (-140 135);
DISPLAY INVISIBLE (-140 135);
FORCEPROP 1 LASTPIN (-150 125) BN 13
J 2
(-138 133);
DISPLAY 0.680851 (-138 133);
PAINT GREEN (-138 133);
FORCEPROP 2 LAST CDS_LIB standard
J 0
(-200 125);
DISPLAY INVISIBLE (-200 125);
FORCEPROP 1 LAST BODY_TYPE PLUMBING
J 2
(-200 175);
DISPLAY 0.872340 (-200 175);
PAINT GREEN (-200 175);
DISPLAY INVISIBLE (-200 175);
FORCEPROP 1 LAST HDL_TAP TRUE
J 2
(-525 0);
DISPLAY 0.872340 (-525 0);
DISPLAY INVISIBLE (-525 0);
FORCEPROP 1 LAST PATH I17
J 2
(-198 125);
DISPLAY 0.872340 (-198 125);
PAINT GREEN (-198 125);
DISPLAY INVISIBLE (-198 125);
FORCEADD TAP..1
R 2
(-200 175);
FORCEPROP 3 LASTPIN (-150 175) SIG_NAME P5E_CPU1_PE3_RX_DN<14>
J 0
(-140 185);
DISPLAY 0.659574 (-140 185);
PAINT MONO (-140 185);
DISPLAY INVISIBLE (-140 185);
FORCEPROP 1 LASTPIN (-150 175) BN 14
J 2
(-138 183);
DISPLAY 0.680851 (-138 183);
PAINT GREEN (-138 183);
FORCEPROP 2 LAST CDS_LIB standard
J 0
(-200 175);
DISPLAY INVISIBLE (-200 175);
FORCEPROP 1 LAST BODY_TYPE PLUMBING
J 2
(-200 225);
DISPLAY 0.872340 (-200 225);
PAINT GREEN (-200 225);
DISPLAY INVISIBLE (-200 225);
FORCEPROP 1 LAST HDL_TAP TRUE
J 2
(-525 50);
DISPLAY 0.872340 (-525 50);
DISPLAY INVISIBLE (-525 50);
FORCEPROP 1 LAST PATH I18
J 2
(-198 175);
DISPLAY 0.872340 (-198 175);
PAINT GREEN (-198 175);
DISPLAY INVISIBLE (-198 175);
FORCEADD TAP..1
R 2
(-200 225);
FORCEPROP 3 LASTPIN (-150 225) SIG_NAME P5E_CPU1_PE3_RX_DN<15>
J 0
(-140 235);
DISPLAY 0.659574 (-140 235);
PAINT MONO (-140 235);
DISPLAY INVISIBLE (-140 235);
FORCEPROP 1 LASTPIN (-150 225) BN 15
J 2
(-138 233);
DISPLAY 0.680851 (-138 233);
PAINT GREEN (-138 233);
FORCEPROP 2 LAST CDS_LIB standard
J 0
(-200 225);
DISPLAY INVISIBLE (-200 225);
FORCEPROP 1 LAST BODY_TYPE PLUMBING
J 2
(-200 275);
DISPLAY 0.872340 (-200 275);
PAINT GREEN (-200 275);
DISPLAY INVISIBLE (-200 275);
FORCEPROP 1 LAST HDL_TAP TRUE
J 2
(-525 100);
DISPLAY 0.872340 (-525 100);
DISPLAY INVISIBLE (-525 100);
FORCEPROP 1 LAST PATH I19
J 2
(-198 225);
DISPLAY 0.872340 (-198 225);
PAINT GREEN (-198 225);
DISPLAY INVISIBLE (-198 225);
FORCEADD TAP..1
R 2
(-200 -475);
FORCEPROP 3 LASTPIN (-150 -475) SIG_NAME P5E_CPU1_PE3_RX_DN<1>
J 0
(-140 -465);
DISPLAY 0.659574 (-140 -465);
PAINT MONO (-140 -465);
DISPLAY INVISIBLE (-140 -465);
FORCEPROP 1 LASTPIN (-150 -475) BN 1
J 2
(-138 -467);
DISPLAY 0.680851 (-138 -467);
PAINT GREEN (-138 -467);
FORCEPROP 2 LAST CDS_LIB standard
J 0
(-200 -475);
DISPLAY INVISIBLE (-200 -475);
FORCEPROP 1 LAST BODY_TYPE PLUMBING
J 2
(-200 -425);
DISPLAY 0.872340 (-200 -425);
PAINT GREEN (-200 -425);
DISPLAY INVISIBLE (-200 -425);
FORCEPROP 1 LAST HDL_TAP TRUE
J 2
(-525 -600);
DISPLAY 0.872340 (-525 -600);
DISPLAY INVISIBLE (-525 -600);
FORCEPROP 1 LAST PATH I2
J 2
(-198 -475);
DISPLAY 0.872340 (-198 -475);
PAINT GREEN (-198 -475);
DISPLAY INVISIBLE (-198 -475);
FORCEADD TAP..1
R 2
(-200 425);
FORCEPROP 3 LASTPIN (-150 425) SIG_NAME P5E_CPU1_PE3_RX_DP<2>
J 0
(-140 435);
DISPLAY 0.659574 (-140 435);
PAINT MONO (-140 435);
DISPLAY INVISIBLE (-140 435);
FORCEPROP 1 LASTPIN (-150 425) BN 2
J 2
(-138 433);
DISPLAY 0.680851 (-138 433);
PAINT GREEN (-138 433);
FORCEPROP 2 LAST CDS_LIB standard
J 0
(-200 425);
DISPLAY INVISIBLE (-200 425);
FORCEPROP 1 LAST BODY_TYPE PLUMBING
J 2
(-200 475);
DISPLAY 0.872340 (-200 475);
PAINT GREEN (-200 475);
DISPLAY INVISIBLE (-200 475);
FORCEPROP 1 LAST HDL_TAP TRUE
J 2
(-525 300);
DISPLAY 0.872340 (-525 300);
DISPLAY INVISIBLE (-525 300);
FORCEPROP 1 LAST PATH I20
J 2
(-198 425);
DISPLAY 0.872340 (-198 425);
PAINT GREEN (-198 425);
DISPLAY INVISIBLE (-198 425);
FORCEADD TAP..1
R 2
(-200 475);
FORCEPROP 3 LASTPIN (-150 475) SIG_NAME P5E_CPU1_PE3_RX_DP<3>
J 0
(-140 485);
DISPLAY 0.659574 (-140 485);
PAINT MONO (-140 485);
DISPLAY INVISIBLE (-140 485);
FORCEPROP 1 LASTPIN (-150 475) BN 3
J 2
(-138 483);
DISPLAY 0.680851 (-138 483);
PAINT GREEN (-138 483);
FORCEPROP 2 LAST CDS_LIB standard
J 0
(-200 475);
DISPLAY INVISIBLE (-200 475);
FORCEPROP 1 LAST BODY_TYPE PLUMBING
J 2
(-200 525);
DISPLAY 0.872340 (-200 525);
PAINT GREEN (-200 525);
DISPLAY INVISIBLE (-200 525);
FORCEPROP 1 LAST HDL_TAP TRUE
J 2
(-525 350);
DISPLAY 0.872340 (-525 350);
DISPLAY INVISIBLE (-525 350);
FORCEPROP 1 LAST PATH I21
J 2
(-198 475);
DISPLAY 0.872340 (-198 475);
PAINT GREEN (-198 475);
DISPLAY INVISIBLE (-198 475);
FORCEADD TAP..1
R 2
(-200 375);
FORCEPROP 3 LASTPIN (-150 375) SIG_NAME P5E_CPU1_PE3_RX_DP<1>
J 0
(-140 385);
DISPLAY 0.659574 (-140 385);
PAINT MONO (-140 385);
DISPLAY INVISIBLE (-140 385);
FORCEPROP 1 LASTPIN (-150 375) BN 1
J 2
(-138 383);
DISPLAY 0.680851 (-138 383);
PAINT GREEN (-138 383);
FORCEPROP 2 LAST CDS_LIB standard
J 0
(-200 375);
DISPLAY INVISIBLE (-200 375);
FORCEPROP 1 LAST BODY_TYPE PLUMBING
J 2
(-200 425);
DISPLAY 0.872340 (-200 425);
PAINT GREEN (-200 425);
DISPLAY INVISIBLE (-200 425);
FORCEPROP 1 LAST HDL_TAP TRUE
J 2
(-525 250);
DISPLAY 0.872340 (-525 250);
DISPLAY INVISIBLE (-525 250);
FORCEPROP 1 LAST PATH I22
J 2
(-198 375);
DISPLAY 0.872340 (-198 375);
PAINT GREEN (-198 375);
DISPLAY INVISIBLE (-198 375);
FORCEADD OFFPAGE..1
(-1425 3025);
FORCEPROP 2 LAST $XR1 141 
J 0
(-1797 3025);
DISPLAY 0.638298 (-1797 3025);
PAINT MONO (-1797 3025);
FORCEPROP 2 LAST $XR0 140 
J 0
(-1677 3025);
DISPLAY 0.638298 (-1677 3025);
PAINT MONO (-1677 3025);
FORCEPROP 2 LAST CDS_LIB standard
J 0
(-1425 3025);
PAINT MONO (-1425 3025);
DISPLAY INVISIBLE (-1425 3025);
FORCEPROP 1 LAST OFFPAGE TRUE
J 0
(-1100 2900);
DISPLAY 0.872340 (-1100 2900);
DISPLAY INVISIBLE (-1100 2900);
FORCEPROP 1 LAST COMMENT_BODY TRUE
J 0
(-1300 2925);
DISPLAY 0.872340 (-1300 2925);
PAINT GREEN (-1300 2925);
DISPLAY INVISIBLE (-1300 2925);
FORCEPROP 2 LAST PATH I223
J 0
(-1675 3075);
DISPLAY 1.021277 (-1675 3075);
DISPLAY INVISIBLE (-1675 3075);
FORCEADD OFFPAGE..1
(-1425 3875);
FORCEPROP 2 LAST $XR1 141 
J 0
(-1797 3875);
DISPLAY 0.638298 (-1797 3875);
PAINT MONO (-1797 3875);
FORCEPROP 2 LAST $XR0 140 
J 0
(-1677 3875);
DISPLAY 0.638298 (-1677 3875);
PAINT MONO (-1677 3875);
FORCEPROP 2 LAST CDS_LIB standard
J 0
(-1425 3875);
PAINT MONO (-1425 3875);
DISPLAY INVISIBLE (-1425 3875);
FORCEPROP 1 LAST OFFPAGE TRUE
J 0
(-1100 3750);
DISPLAY 0.872340 (-1100 3750);
DISPLAY INVISIBLE (-1100 3750);
FORCEPROP 1 LAST COMMENT_BODY TRUE
J 0
(-1300 3775);
DISPLAY 0.872340 (-1300 3775);
PAINT GREEN (-1300 3775);
DISPLAY INVISIBLE (-1300 3775);
FORCEPROP 2 LAST PATH I224
J 0
(-1675 3925);
DISPLAY 1.021277 (-1675 3925);
DISPLAY INVISIBLE (-1675 3925);
FORCEADD TAP..1
R 2
(-175 2300);
FORCEPROP 3 LASTPIN (-125 2300) SIG_NAME P5E_CPU1_PE2_RX_DN<1>
J 0
(-115 2310);
DISPLAY 0.659574 (-115 2310);
PAINT MONO (-115 2310);
DISPLAY INVISIBLE (-115 2310);
FORCEPROP 1 LASTPIN (-125 2300) BN 1
J 2
(-113 2308);
DISPLAY 0.680851 (-113 2308);
PAINT GREEN (-113 2308);
FORCEPROP 2 LAST CDS_LIB standard
J 0
(-175 2300);
DISPLAY INVISIBLE (-175 2300);
FORCEPROP 1 LAST BODY_TYPE PLUMBING
J 2
(-175 2350);
DISPLAY 0.872340 (-175 2350);
PAINT GREEN (-175 2350);
DISPLAY INVISIBLE (-175 2350);
FORCEPROP 1 LAST HDL_TAP TRUE
J 2
(-500 2175);
DISPLAY 0.872340 (-500 2175);
DISPLAY INVISIBLE (-500 2175);
FORCEPROP 1 LAST PATH I225
J 2
(-173 2300);
DISPLAY 0.872340 (-173 2300);
PAINT GREEN (-173 2300);
DISPLAY INVISIBLE (-173 2300);
FORCEADD TAP..1
R 2
(-175 2250);
FORCEPROP 3 LASTPIN (-125 2250) SIG_NAME P5E_CPU1_PE2_RX_DN<0>
J 0
(-115 2260);
DISPLAY 0.659574 (-115 2260);
PAINT MONO (-115 2260);
DISPLAY INVISIBLE (-115 2260);
FORCEPROP 1 LASTPIN (-125 2250) BN 0
J 2
(-113 2258);
DISPLAY 0.680851 (-113 2258);
PAINT GREEN (-113 2258);
FORCEPROP 2 LAST CDS_LIB standard
J 0
(-175 2250);
DISPLAY INVISIBLE (-175 2250);
FORCEPROP 1 LAST BODY_TYPE PLUMBING
J 2
(-175 2300);
DISPLAY 0.872340 (-175 2300);
PAINT GREEN (-175 2300);
DISPLAY INVISIBLE (-175 2300);
FORCEPROP 1 LAST HDL_TAP TRUE
J 2
(-500 2125);
DISPLAY 0.872340 (-500 2125);
DISPLAY INVISIBLE (-500 2125);
FORCEPROP 1 LAST PATH I226
J 2
(-173 2250);
DISPLAY 0.872340 (-173 2250);
PAINT GREEN (-173 2250);
DISPLAY INVISIBLE (-173 2250);
FORCEADD TAP..1
R 2
(-175 2350);
FORCEPROP 3 LASTPIN (-125 2350) SIG_NAME P5E_CPU1_PE2_RX_DN<2>
J 0
(-115 2360);
DISPLAY 0.659574 (-115 2360);
PAINT MONO (-115 2360);
DISPLAY INVISIBLE (-115 2360);
FORCEPROP 1 LASTPIN (-125 2350) BN 2
J 2
(-113 2358);
DISPLAY 0.680851 (-113 2358);
PAINT GREEN (-113 2358);
FORCEPROP 2 LAST CDS_LIB standard
J 0
(-175 2350);
DISPLAY INVISIBLE (-175 2350);
FORCEPROP 1 LAST BODY_TYPE PLUMBING
J 2
(-175 2400);
DISPLAY 0.872340 (-175 2400);
PAINT GREEN (-175 2400);
DISPLAY INVISIBLE (-175 2400);
FORCEPROP 1 LAST HDL_TAP TRUE
J 2
(-500 2225);
DISPLAY 0.872340 (-500 2225);
DISPLAY INVISIBLE (-500 2225);
FORCEPROP 1 LAST PATH I227
J 2
(-173 2350);
DISPLAY 0.872340 (-173 2350);
PAINT GREEN (-173 2350);
DISPLAY INVISIBLE (-173 2350);
FORCEADD TAP..1
R 2
(-175 2450);
FORCEPROP 3 LASTPIN (-125 2450) SIG_NAME P5E_CPU1_PE2_RX_DN<4>
J 0
(-115 2460);
DISPLAY 0.659574 (-115 2460);
PAINT MONO (-115 2460);
DISPLAY INVISIBLE (-115 2460);
FORCEPROP 1 LASTPIN (-125 2450) BN 4
J 2
(-113 2458);
DISPLAY 0.680851 (-113 2458);
PAINT GREEN (-113 2458);
FORCEPROP 2 LAST CDS_LIB standard
J 0
(-175 2450);
DISPLAY INVISIBLE (-175 2450);
FORCEPROP 1 LAST BODY_TYPE PLUMBING
J 2
(-175 2500);
DISPLAY 0.872340 (-175 2500);
PAINT GREEN (-175 2500);
DISPLAY INVISIBLE (-175 2500);
FORCEPROP 1 LAST HDL_TAP TRUE
J 2
(-500 2325);
DISPLAY 0.872340 (-500 2325);
DISPLAY INVISIBLE (-500 2325);
FORCEPROP 1 LAST PATH I228
J 2
(-173 2450);
DISPLAY 0.872340 (-173 2450);
PAINT GREEN (-173 2450);
DISPLAY INVISIBLE (-173 2450);
FORCEADD TAP..1
R 2
(-175 2400);
FORCEPROP 3 LASTPIN (-125 2400) SIG_NAME P5E_CPU1_PE2_RX_DN<3>
J 0
(-115 2410);
DISPLAY 0.659574 (-115 2410);
PAINT MONO (-115 2410);
DISPLAY INVISIBLE (-115 2410);
FORCEPROP 1 LASTPIN (-125 2400) BN 3
J 2
(-113 2408);
DISPLAY 0.680851 (-113 2408);
PAINT GREEN (-113 2408);
FORCEPROP 2 LAST CDS_LIB standard
J 0
(-175 2400);
DISPLAY INVISIBLE (-175 2400);
FORCEPROP 1 LAST BODY_TYPE PLUMBING
J 2
(-175 2450);
DISPLAY 0.872340 (-175 2450);
PAINT GREEN (-175 2450);
DISPLAY INVISIBLE (-175 2450);
FORCEPROP 1 LAST HDL_TAP TRUE
J 2
(-500 2275);
DISPLAY 0.872340 (-500 2275);
DISPLAY INVISIBLE (-500 2275);
FORCEPROP 1 LAST PATH I229
J 2
(-173 2400);
DISPLAY 0.872340 (-173 2400);
PAINT GREEN (-173 2400);
DISPLAY INVISIBLE (-173 2400);
FORCEADD TAP..1
R 2
(-200 325);
FORCEPROP 3 LASTPIN (-150 325) SIG_NAME P5E_CPU1_PE3_RX_DP<0>
J 0
(-140 335);
DISPLAY 0.659574 (-140 335);
PAINT MONO (-140 335);
DISPLAY INVISIBLE (-140 335);
FORCEPROP 1 LASTPIN (-150 325) BN 0
J 2
(-138 333);
DISPLAY 0.680851 (-138 333);
PAINT GREEN (-138 333);
FORCEPROP 2 LAST CDS_LIB standard
J 0
(-200 325);
DISPLAY INVISIBLE (-200 325);
FORCEPROP 1 LAST BODY_TYPE PLUMBING
J 2
(-200 375);
DISPLAY 0.872340 (-200 375);
PAINT GREEN (-200 375);
DISPLAY INVISIBLE (-200 375);
FORCEPROP 1 LAST HDL_TAP TRUE
J 2
(-525 200);
DISPLAY 0.872340 (-525 200);
DISPLAY INVISIBLE (-525 200);
FORCEPROP 1 LAST PATH I23
J 2
(-198 325);
DISPLAY 0.872340 (-198 325);
PAINT GREEN (-198 325);
DISPLAY INVISIBLE (-198 325);
FORCEADD TAP..1
R 2
(-175 2550);
FORCEPROP 3 LASTPIN (-125 2550) SIG_NAME P5E_CPU1_PE2_RX_DN<6>
J 0
(-115 2560);
DISPLAY 0.659574 (-115 2560);
PAINT MONO (-115 2560);
DISPLAY INVISIBLE (-115 2560);
FORCEPROP 1 LASTPIN (-125 2550) BN 6
J 2
(-113 2558);
DISPLAY 0.680851 (-113 2558);
PAINT GREEN (-113 2558);
FORCEPROP 2 LAST CDS_LIB standard
J 0
(-175 2550);
DISPLAY INVISIBLE (-175 2550);
FORCEPROP 1 LAST BODY_TYPE PLUMBING
J 2
(-175 2600);
DISPLAY 0.872340 (-175 2600);
PAINT GREEN (-175 2600);
DISPLAY INVISIBLE (-175 2600);
FORCEPROP 1 LAST HDL_TAP TRUE
J 2
(-500 2425);
DISPLAY 0.872340 (-500 2425);
DISPLAY INVISIBLE (-500 2425);
FORCEPROP 1 LAST PATH I230
J 2
(-173 2550);
DISPLAY 0.872340 (-173 2550);
PAINT GREEN (-173 2550);
DISPLAY INVISIBLE (-173 2550);
FORCEADD TAP..1
R 2
(-175 2500);
FORCEPROP 3 LASTPIN (-125 2500) SIG_NAME P5E_CPU1_PE2_RX_DN<5>
J 0
(-115 2510);
DISPLAY 0.659574 (-115 2510);
PAINT MONO (-115 2510);
DISPLAY INVISIBLE (-115 2510);
FORCEPROP 1 LASTPIN (-125 2500) BN 5
J 2
(-113 2508);
DISPLAY 0.680851 (-113 2508);
PAINT GREEN (-113 2508);
FORCEPROP 2 LAST CDS_LIB standard
J 0
(-175 2500);
DISPLAY INVISIBLE (-175 2500);
FORCEPROP 1 LAST BODY_TYPE PLUMBING
J 2
(-175 2550);
DISPLAY 0.872340 (-175 2550);
PAINT GREEN (-175 2550);
DISPLAY INVISIBLE (-175 2550);
FORCEPROP 1 LAST HDL_TAP TRUE
J 2
(-500 2375);
DISPLAY 0.872340 (-500 2375);
DISPLAY INVISIBLE (-500 2375);
FORCEPROP 1 LAST PATH I231
J 2
(-173 2500);
DISPLAY 0.872340 (-173 2500);
PAINT GREEN (-173 2500);
DISPLAY INVISIBLE (-173 2500);
FORCEADD TAP..1
R 2
(-175 2600);
FORCEPROP 3 LASTPIN (-125 2600) SIG_NAME P5E_CPU1_PE2_RX_DN<7>
J 0
(-115 2610);
DISPLAY 0.659574 (-115 2610);
PAINT MONO (-115 2610);
DISPLAY INVISIBLE (-115 2610);
FORCEPROP 1 LASTPIN (-125 2600) BN 7
J 2
(-113 2608);
DISPLAY 0.680851 (-113 2608);
PAINT GREEN (-113 2608);
FORCEPROP 2 LAST CDS_LIB standard
J 0
(-175 2600);
DISPLAY INVISIBLE (-175 2600);
FORCEPROP 1 LAST BODY_TYPE PLUMBING
J 2
(-175 2650);
DISPLAY 0.872340 (-175 2650);
PAINT GREEN (-175 2650);
DISPLAY INVISIBLE (-175 2650);
FORCEPROP 1 LAST HDL_TAP TRUE
J 2
(-500 2475);
DISPLAY 0.872340 (-500 2475);
DISPLAY INVISIBLE (-500 2475);
FORCEPROP 1 LAST PATH I232
J 2
(-173 2600);
DISPLAY 0.872340 (-173 2600);
PAINT GREEN (-173 2600);
DISPLAY INVISIBLE (-173 2600);
FORCEADD TAP..1
R 2
(-175 2700);
FORCEPROP 3 LASTPIN (-125 2700) SIG_NAME P5E_CPU1_PE2_RX_DN<9>
J 0
(-115 2710);
DISPLAY 0.659574 (-115 2710);
PAINT MONO (-115 2710);
DISPLAY INVISIBLE (-115 2710);
FORCEPROP 1 LASTPIN (-125 2700) BN 9
J 2
(-113 2708);
DISPLAY 0.680851 (-113 2708);
PAINT GREEN (-113 2708);
FORCEPROP 2 LAST CDS_LIB standard
J 0
(-175 2700);
DISPLAY INVISIBLE (-175 2700);
FORCEPROP 1 LAST BODY_TYPE PLUMBING
J 2
(-175 2750);
DISPLAY 0.872340 (-175 2750);
PAINT GREEN (-175 2750);
DISPLAY INVISIBLE (-175 2750);
FORCEPROP 1 LAST HDL_TAP TRUE
J 2
(-500 2575);
DISPLAY 0.872340 (-500 2575);
DISPLAY INVISIBLE (-500 2575);
FORCEPROP 1 LAST PATH I233
J 2
(-173 2700);
DISPLAY 0.872340 (-173 2700);
PAINT GREEN (-173 2700);
DISPLAY INVISIBLE (-173 2700);
FORCEADD TAP..1
R 2
(-175 2650);
FORCEPROP 3 LASTPIN (-125 2650) SIG_NAME P5E_CPU1_PE2_RX_DN<8>
J 0
(-115 2660);
DISPLAY 0.659574 (-115 2660);
PAINT MONO (-115 2660);
DISPLAY INVISIBLE (-115 2660);
FORCEPROP 1 LASTPIN (-125 2650) BN 8
J 2
(-113 2658);
DISPLAY 0.680851 (-113 2658);
PAINT GREEN (-113 2658);
FORCEPROP 2 LAST CDS_LIB standard
J 0
(-175 2650);
DISPLAY INVISIBLE (-175 2650);
FORCEPROP 1 LAST BODY_TYPE PLUMBING
J 2
(-175 2700);
DISPLAY 0.872340 (-175 2700);
PAINT GREEN (-175 2700);
DISPLAY INVISIBLE (-175 2700);
FORCEPROP 1 LAST HDL_TAP TRUE
J 2
(-500 2525);
DISPLAY 0.872340 (-500 2525);
DISPLAY INVISIBLE (-500 2525);
FORCEPROP 1 LAST PATH I234
J 2
(-173 2650);
DISPLAY 0.872340 (-173 2650);
PAINT GREEN (-173 2650);
DISPLAY INVISIBLE (-173 2650);
FORCEADD TAP..1
R 2
(-175 2850);
FORCEPROP 3 LASTPIN (-125 2850) SIG_NAME P5E_CPU1_PE2_RX_DN<12>
J 0
(-115 2860);
DISPLAY 0.659574 (-115 2860);
PAINT MONO (-115 2860);
DISPLAY INVISIBLE (-115 2860);
FORCEPROP 1 LASTPIN (-125 2850) BN 12
J 2
(-113 2858);
DISPLAY 0.680851 (-113 2858);
PAINT GREEN (-113 2858);
FORCEPROP 2 LAST CDS_LIB standard
J 0
(-175 2850);
DISPLAY INVISIBLE (-175 2850);
FORCEPROP 1 LAST BODY_TYPE PLUMBING
J 2
(-175 2900);
DISPLAY 0.872340 (-175 2900);
PAINT GREEN (-175 2900);
DISPLAY INVISIBLE (-175 2900);
FORCEPROP 1 LAST HDL_TAP TRUE
J 2
(-500 2725);
DISPLAY 0.872340 (-500 2725);
DISPLAY INVISIBLE (-500 2725);
FORCEPROP 1 LAST PATH I235
J 2
(-173 2850);
DISPLAY 0.872340 (-173 2850);
PAINT GREEN (-173 2850);
DISPLAY INVISIBLE (-173 2850);
FORCEADD TAP..1
R 2
(-175 3100);
FORCEPROP 3 LASTPIN (-125 3100) SIG_NAME P5E_CPU1_PE2_RX_DP<0>
J 0
(-115 3110);
DISPLAY 0.659574 (-115 3110);
PAINT MONO (-115 3110);
DISPLAY INVISIBLE (-115 3110);
FORCEPROP 1 LASTPIN (-125 3100) BN 0
J 2
(-113 3108);
DISPLAY 0.680851 (-113 3108);
PAINT GREEN (-113 3108);
FORCEPROP 2 LAST CDS_LIB standard
J 0
(-175 3100);
DISPLAY INVISIBLE (-175 3100);
FORCEPROP 1 LAST BODY_TYPE PLUMBING
J 2
(-175 3150);
DISPLAY 0.872340 (-175 3150);
PAINT GREEN (-175 3150);
DISPLAY INVISIBLE (-175 3150);
FORCEPROP 1 LAST HDL_TAP TRUE
J 2
(-500 2975);
DISPLAY 0.872340 (-500 2975);
DISPLAY INVISIBLE (-500 2975);
FORCEPROP 1 LAST PATH I236
J 2
(-173 3100);
DISPLAY 0.872340 (-173 3100);
PAINT GREEN (-173 3100);
DISPLAY INVISIBLE (-173 3100);
FORCEADD TAP..1
R 2
(-175 3200);
FORCEPROP 3 LASTPIN (-125 3200) SIG_NAME P5E_CPU1_PE2_RX_DP<2>
J 0
(-115 3210);
DISPLAY 0.659574 (-115 3210);
PAINT MONO (-115 3210);
DISPLAY INVISIBLE (-115 3210);
FORCEPROP 1 LASTPIN (-125 3200) BN 2
J 2
(-113 3208);
DISPLAY 0.680851 (-113 3208);
PAINT GREEN (-113 3208);
FORCEPROP 2 LAST CDS_LIB standard
J 0
(-175 3200);
DISPLAY INVISIBLE (-175 3200);
FORCEPROP 1 LAST BODY_TYPE PLUMBING
J 2
(-175 3250);
DISPLAY 0.872340 (-175 3250);
PAINT GREEN (-175 3250);
DISPLAY INVISIBLE (-175 3250);
FORCEPROP 1 LAST HDL_TAP TRUE
J 2
(-500 3075);
DISPLAY 0.872340 (-500 3075);
DISPLAY INVISIBLE (-500 3075);
FORCEPROP 1 LAST PATH I237
J 2
(-173 3200);
DISPLAY 0.872340 (-173 3200);
PAINT GREEN (-173 3200);
DISPLAY INVISIBLE (-173 3200);
FORCEADD TAP..1
R 2
(-175 3150);
FORCEPROP 3 LASTPIN (-125 3150) SIG_NAME P5E_CPU1_PE2_RX_DP<1>
J 0
(-115 3160);
DISPLAY 0.659574 (-115 3160);
PAINT MONO (-115 3160);
DISPLAY INVISIBLE (-115 3160);
FORCEPROP 1 LASTPIN (-125 3150) BN 1
J 2
(-113 3158);
DISPLAY 0.680851 (-113 3158);
PAINT GREEN (-113 3158);
FORCEPROP 2 LAST CDS_LIB standard
J 0
(-175 3150);
DISPLAY INVISIBLE (-175 3150);
FORCEPROP 1 LAST BODY_TYPE PLUMBING
J 2
(-175 3200);
DISPLAY 0.872340 (-175 3200);
PAINT GREEN (-175 3200);
DISPLAY INVISIBLE (-175 3200);
FORCEPROP 1 LAST HDL_TAP TRUE
J 2
(-500 3025);
DISPLAY 0.872340 (-500 3025);
DISPLAY INVISIBLE (-500 3025);
FORCEPROP 1 LAST PATH I238
J 2
(-173 3150);
DISPLAY 0.872340 (-173 3150);
PAINT GREEN (-173 3150);
DISPLAY INVISIBLE (-173 3150);
FORCEADD TAP..1
R 2
(-175 3250);
FORCEPROP 3 LASTPIN (-125 3250) SIG_NAME P5E_CPU1_PE2_RX_DP<3>
J 0
(-115 3260);
DISPLAY 0.659574 (-115 3260);
PAINT MONO (-115 3260);
DISPLAY INVISIBLE (-115 3260);
FORCEPROP 1 LASTPIN (-125 3250) BN 3
J 2
(-113 3258);
DISPLAY 0.680851 (-113 3258);
PAINT GREEN (-113 3258);
FORCEPROP 2 LAST CDS_LIB standard
J 0
(-175 3250);
DISPLAY INVISIBLE (-175 3250);
FORCEPROP 1 LAST BODY_TYPE PLUMBING
J 2
(-175 3300);
DISPLAY 0.872340 (-175 3300);
PAINT GREEN (-175 3300);
DISPLAY INVISIBLE (-175 3300);
FORCEPROP 1 LAST HDL_TAP TRUE
J 2
(-500 3125);
DISPLAY 0.872340 (-500 3125);
DISPLAY INVISIBLE (-500 3125);
FORCEPROP 1 LAST PATH I239
J 2
(-173 3250);
DISPLAY 0.872340 (-173 3250);
PAINT GREEN (-173 3250);
DISPLAY INVISIBLE (-173 3250);
FORCEADD TAP..1
R 2
(-200 525);
FORCEPROP 3 LASTPIN (-150 525) SIG_NAME P5E_CPU1_PE3_RX_DP<4>
J 0
(-140 535);
DISPLAY 0.659574 (-140 535);
PAINT MONO (-140 535);
DISPLAY INVISIBLE (-140 535);
FORCEPROP 1 LASTPIN (-150 525) BN 4
J 2
(-138 533);
DISPLAY 0.680851 (-138 533);
PAINT GREEN (-138 533);
FORCEPROP 2 LAST CDS_LIB standard
J 0
(-200 525);
DISPLAY INVISIBLE (-200 525);
FORCEPROP 1 LAST BODY_TYPE PLUMBING
J 2
(-200 575);
DISPLAY 0.872340 (-200 575);
PAINT GREEN (-200 575);
DISPLAY INVISIBLE (-200 575);
FORCEPROP 1 LAST HDL_TAP TRUE
J 2
(-525 400);
DISPLAY 0.872340 (-525 400);
DISPLAY INVISIBLE (-525 400);
FORCEPROP 1 LAST PATH I24
J 2
(-198 525);
DISPLAY 0.872340 (-198 525);
PAINT GREEN (-198 525);
DISPLAY INVISIBLE (-198 525);
FORCEADD TAP..1
R 2
(-175 3350);
FORCEPROP 3 LASTPIN (-125 3350) SIG_NAME P5E_CPU1_PE2_RX_DP<5>
J 0
(-115 3360);
DISPLAY 0.659574 (-115 3360);
PAINT MONO (-115 3360);
DISPLAY INVISIBLE (-115 3360);
FORCEPROP 1 LASTPIN (-125 3350) BN 5
J 2
(-113 3358);
DISPLAY 0.680851 (-113 3358);
PAINT GREEN (-113 3358);
FORCEPROP 2 LAST CDS_LIB standard
J 0
(-175 3350);
DISPLAY INVISIBLE (-175 3350);
FORCEPROP 1 LAST BODY_TYPE PLUMBING
J 2
(-175 3400);
DISPLAY 0.872340 (-175 3400);
PAINT GREEN (-175 3400);
DISPLAY INVISIBLE (-175 3400);
FORCEPROP 1 LAST HDL_TAP TRUE
J 2
(-500 3225);
DISPLAY 0.872340 (-500 3225);
DISPLAY INVISIBLE (-500 3225);
FORCEPROP 1 LAST PATH I240
J 2
(-173 3350);
DISPLAY 0.872340 (-173 3350);
PAINT GREEN (-173 3350);
DISPLAY INVISIBLE (-173 3350);
FORCEADD TAP..1
R 2
(-175 3300);
FORCEPROP 3 LASTPIN (-125 3300) SIG_NAME P5E_CPU1_PE2_RX_DP<4>
J 0
(-115 3310);
DISPLAY 0.659574 (-115 3310);
PAINT MONO (-115 3310);
DISPLAY INVISIBLE (-115 3310);
FORCEPROP 1 LASTPIN (-125 3300) BN 4
J 2
(-113 3308);
DISPLAY 0.680851 (-113 3308);
PAINT GREEN (-113 3308);
FORCEPROP 2 LAST CDS_LIB standard
J 0
(-175 3300);
DISPLAY INVISIBLE (-175 3300);
FORCEPROP 1 LAST BODY_TYPE PLUMBING
J 2
(-175 3350);
DISPLAY 0.872340 (-175 3350);
PAINT GREEN (-175 3350);
DISPLAY INVISIBLE (-175 3350);
FORCEPROP 1 LAST HDL_TAP TRUE
J 2
(-500 3175);
DISPLAY 0.872340 (-500 3175);
DISPLAY INVISIBLE (-500 3175);
FORCEPROP 1 LAST PATH I241
J 2
(-173 3300);
DISPLAY 0.872340 (-173 3300);
PAINT GREEN (-173 3300);
DISPLAY INVISIBLE (-173 3300);
FORCEADD TAP..1
R 2
(-175 3450);
FORCEPROP 3 LASTPIN (-125 3450) SIG_NAME P5E_CPU1_PE2_RX_DP<7>
J 0
(-115 3460);
DISPLAY 0.659574 (-115 3460);
PAINT MONO (-115 3460);
DISPLAY INVISIBLE (-115 3460);
FORCEPROP 1 LASTPIN (-125 3450) BN 7
J 2
(-113 3458);
DISPLAY 0.680851 (-113 3458);
PAINT GREEN (-113 3458);
FORCEPROP 2 LAST CDS_LIB standard
J 0
(-175 3450);
DISPLAY INVISIBLE (-175 3450);
FORCEPROP 1 LAST BODY_TYPE PLUMBING
J 2
(-175 3500);
DISPLAY 0.872340 (-175 3500);
PAINT GREEN (-175 3500);
DISPLAY INVISIBLE (-175 3500);
FORCEPROP 1 LAST HDL_TAP TRUE
J 2
(-500 3325);
DISPLAY 0.872340 (-500 3325);
DISPLAY INVISIBLE (-500 3325);
FORCEPROP 1 LAST PATH I242
J 2
(-173 3450);
DISPLAY 0.872340 (-173 3450);
PAINT GREEN (-173 3450);
DISPLAY INVISIBLE (-173 3450);
FORCEADD TAP..1
R 2
(-175 3400);
FORCEPROP 3 LASTPIN (-125 3400) SIG_NAME P5E_CPU1_PE2_RX_DP<6>
J 0
(-115 3410);
DISPLAY 0.659574 (-115 3410);
PAINT MONO (-115 3410);
DISPLAY INVISIBLE (-115 3410);
FORCEPROP 1 LASTPIN (-125 3400) BN 6
J 2
(-113 3408);
DISPLAY 0.680851 (-113 3408);
PAINT GREEN (-113 3408);
FORCEPROP 2 LAST CDS_LIB standard
J 0
(-175 3400);
DISPLAY INVISIBLE (-175 3400);
FORCEPROP 1 LAST BODY_TYPE PLUMBING
J 2
(-175 3450);
DISPLAY 0.872340 (-175 3450);
PAINT GREEN (-175 3450);
DISPLAY INVISIBLE (-175 3450);
FORCEPROP 1 LAST HDL_TAP TRUE
J 2
(-500 3275);
DISPLAY 0.872340 (-500 3275);
DISPLAY INVISIBLE (-500 3275);
FORCEPROP 1 LAST PATH I243
J 2
(-173 3400);
DISPLAY 0.872340 (-173 3400);
PAINT GREEN (-173 3400);
DISPLAY INVISIBLE (-173 3400);
FORCEADD TAP..1
R 2
(-175 3500);
FORCEPROP 3 LASTPIN (-125 3500) SIG_NAME P5E_CPU1_PE2_RX_DP<8>
J 0
(-115 3510);
DISPLAY 0.659574 (-115 3510);
PAINT MONO (-115 3510);
DISPLAY INVISIBLE (-115 3510);
FORCEPROP 1 LASTPIN (-125 3500) BN 8
J 2
(-113 3508);
DISPLAY 0.680851 (-113 3508);
PAINT GREEN (-113 3508);
FORCEPROP 2 LAST CDS_LIB standard
J 0
(-175 3500);
DISPLAY INVISIBLE (-175 3500);
FORCEPROP 1 LAST BODY_TYPE PLUMBING
J 2
(-175 3550);
DISPLAY 0.872340 (-175 3550);
PAINT GREEN (-175 3550);
DISPLAY INVISIBLE (-175 3550);
FORCEPROP 1 LAST HDL_TAP TRUE
J 2
(-500 3375);
DISPLAY 0.872340 (-500 3375);
DISPLAY INVISIBLE (-500 3375);
FORCEPROP 1 LAST PATH I244
J 2
(-173 3500);
DISPLAY 0.872340 (-173 3500);
PAINT GREEN (-173 3500);
DISPLAY INVISIBLE (-173 3500);
FORCEADD TAP..1
R 2
(-175 3600);
FORCEPROP 3 LASTPIN (-125 3600) SIG_NAME P5E_CPU1_PE2_RX_DP<10>
J 0
(-115 3610);
DISPLAY 0.659574 (-115 3610);
PAINT MONO (-115 3610);
DISPLAY INVISIBLE (-115 3610);
FORCEPROP 1 LASTPIN (-125 3600) BN 10
J 2
(-113 3608);
DISPLAY 0.680851 (-113 3608);
PAINT GREEN (-113 3608);
FORCEPROP 2 LAST CDS_LIB standard
J 0
(-175 3600);
DISPLAY INVISIBLE (-175 3600);
FORCEPROP 1 LAST BODY_TYPE PLUMBING
J 2
(-175 3650);
DISPLAY 0.872340 (-175 3650);
PAINT GREEN (-175 3650);
DISPLAY INVISIBLE (-175 3650);
FORCEPROP 1 LAST HDL_TAP TRUE
J 2
(-500 3475);
DISPLAY 0.872340 (-500 3475);
DISPLAY INVISIBLE (-500 3475);
FORCEPROP 1 LAST PATH I245
J 2
(-173 3600);
DISPLAY 0.872340 (-173 3600);
PAINT GREEN (-173 3600);
DISPLAY INVISIBLE (-173 3600);
FORCEADD TAP..1
R 2
(-175 3550);
FORCEPROP 3 LASTPIN (-125 3550) SIG_NAME P5E_CPU1_PE2_RX_DP<9>
J 0
(-115 3560);
DISPLAY 0.659574 (-115 3560);
PAINT MONO (-115 3560);
DISPLAY INVISIBLE (-115 3560);
FORCEPROP 1 LASTPIN (-125 3550) BN 9
J 2
(-113 3558);
DISPLAY 0.680851 (-113 3558);
PAINT GREEN (-113 3558);
FORCEPROP 2 LAST CDS_LIB standard
J 0
(-175 3550);
DISPLAY INVISIBLE (-175 3550);
FORCEPROP 1 LAST BODY_TYPE PLUMBING
J 2
(-175 3600);
DISPLAY 0.872340 (-175 3600);
PAINT GREEN (-175 3600);
DISPLAY INVISIBLE (-175 3600);
FORCEPROP 1 LAST HDL_TAP TRUE
J 2
(-500 3425);
DISPLAY 0.872340 (-500 3425);
DISPLAY INVISIBLE (-500 3425);
FORCEPROP 1 LAST PATH I246
J 2
(-173 3550);
DISPLAY 0.872340 (-173 3550);
PAINT GREEN (-173 3550);
DISPLAY INVISIBLE (-173 3550);
FORCEADD TAP..1
R 2
(-175 3700);
FORCEPROP 3 LASTPIN (-125 3700) SIG_NAME P5E_CPU1_PE2_RX_DP<12>
J 0
(-115 3710);
DISPLAY 0.659574 (-115 3710);
PAINT MONO (-115 3710);
DISPLAY INVISIBLE (-115 3710);
FORCEPROP 1 LASTPIN (-125 3700) BN 12
J 2
(-113 3708);
DISPLAY 0.680851 (-113 3708);
PAINT GREEN (-113 3708);
FORCEPROP 2 LAST CDS_LIB standard
J 0
(-175 3700);
DISPLAY INVISIBLE (-175 3700);
FORCEPROP 1 LAST BODY_TYPE PLUMBING
J 2
(-175 3750);
DISPLAY 0.872340 (-175 3750);
PAINT GREEN (-175 3750);
DISPLAY INVISIBLE (-175 3750);
FORCEPROP 1 LAST HDL_TAP TRUE
J 2
(-500 3575);
DISPLAY 0.872340 (-500 3575);
DISPLAY INVISIBLE (-500 3575);
FORCEPROP 1 LAST PATH I247
J 2
(-173 3700);
DISPLAY 0.872340 (-173 3700);
PAINT GREEN (-173 3700);
DISPLAY INVISIBLE (-173 3700);
FORCEADD TAP..1
R 2
(-175 3650);
FORCEPROP 3 LASTPIN (-125 3650) SIG_NAME P5E_CPU1_PE2_RX_DP<11>
J 0
(-115 3660);
DISPLAY 0.659574 (-115 3660);
PAINT MONO (-115 3660);
DISPLAY INVISIBLE (-115 3660);
FORCEPROP 1 LASTPIN (-125 3650) BN 11
J 2
(-113 3658);
DISPLAY 0.680851 (-113 3658);
PAINT GREEN (-113 3658);
FORCEPROP 2 LAST CDS_LIB standard
J 0
(-175 3650);
DISPLAY INVISIBLE (-175 3650);
FORCEPROP 1 LAST BODY_TYPE PLUMBING
J 2
(-175 3700);
DISPLAY 0.872340 (-175 3700);
PAINT GREEN (-175 3700);
DISPLAY INVISIBLE (-175 3700);
FORCEPROP 1 LAST HDL_TAP TRUE
J 2
(-500 3525);
DISPLAY 0.872340 (-500 3525);
DISPLAY INVISIBLE (-500 3525);
FORCEPROP 1 LAST PATH I248
J 2
(-173 3650);
DISPLAY 0.872340 (-173 3650);
PAINT GREEN (-173 3650);
DISPLAY INVISIBLE (-173 3650);
FORCEADD TAP..1
R 2
(-175 3750);
FORCEPROP 3 LASTPIN (-125 3750) SIG_NAME P5E_CPU1_PE2_RX_DP<13>
J 0
(-115 3760);
DISPLAY 0.659574 (-115 3760);
PAINT MONO (-115 3760);
DISPLAY INVISIBLE (-115 3760);
FORCEPROP 1 LASTPIN (-125 3750) BN 13
J 2
(-113 3758);
DISPLAY 0.680851 (-113 3758);
PAINT GREEN (-113 3758);
FORCEPROP 2 LAST CDS_LIB standard
J 0
(-175 3750);
DISPLAY INVISIBLE (-175 3750);
FORCEPROP 1 LAST BODY_TYPE PLUMBING
J 2
(-175 3800);
DISPLAY 0.872340 (-175 3800);
PAINT GREEN (-175 3800);
DISPLAY INVISIBLE (-175 3800);
FORCEPROP 1 LAST HDL_TAP TRUE
J 2
(-500 3625);
DISPLAY 0.872340 (-500 3625);
DISPLAY INVISIBLE (-500 3625);
FORCEPROP 1 LAST PATH I249
J 2
(-173 3750);
DISPLAY 0.872340 (-173 3750);
PAINT GREEN (-173 3750);
DISPLAY INVISIBLE (-173 3750);
FORCEADD TAP..1
R 2
(-200 575);
FORCEPROP 3 LASTPIN (-150 575) SIG_NAME P5E_CPU1_PE3_RX_DP<5>
J 0
(-140 585);
DISPLAY 0.659574 (-140 585);
PAINT MONO (-140 585);
DISPLAY INVISIBLE (-140 585);
FORCEPROP 1 LASTPIN (-150 575) BN 5
J 2
(-138 583);
DISPLAY 0.680851 (-138 583);
PAINT GREEN (-138 583);
FORCEPROP 2 LAST CDS_LIB standard
J 0
(-200 575);
DISPLAY INVISIBLE (-200 575);
FORCEPROP 1 LAST BODY_TYPE PLUMBING
J 2
(-200 625);
DISPLAY 0.872340 (-200 625);
PAINT GREEN (-200 625);
DISPLAY INVISIBLE (-200 625);
FORCEPROP 1 LAST HDL_TAP TRUE
J 2
(-525 450);
DISPLAY 0.872340 (-525 450);
DISPLAY INVISIBLE (-525 450);
FORCEPROP 1 LAST PATH I25
J 2
(-198 575);
DISPLAY 0.872340 (-198 575);
PAINT GREEN (-198 575);
DISPLAY INVISIBLE (-198 575);
FORCEADD TAP..1
R 2
(-175 3850);
FORCEPROP 3 LASTPIN (-125 3850) SIG_NAME P5E_CPU1_PE2_RX_DP<15>
J 0
(-115 3860);
DISPLAY 0.659574 (-115 3860);
PAINT MONO (-115 3860);
DISPLAY INVISIBLE (-115 3860);
FORCEPROP 1 LASTPIN (-125 3850) BN 15
J 2
(-113 3858);
DISPLAY 0.680851 (-113 3858);
PAINT GREEN (-113 3858);
FORCEPROP 2 LAST CDS_LIB standard
J 0
(-175 3850);
DISPLAY INVISIBLE (-175 3850);
FORCEPROP 1 LAST BODY_TYPE PLUMBING
J 2
(-175 3900);
DISPLAY 0.872340 (-175 3900);
PAINT GREEN (-175 3900);
DISPLAY INVISIBLE (-175 3900);
FORCEPROP 1 LAST HDL_TAP TRUE
J 2
(-500 3725);
DISPLAY 0.872340 (-500 3725);
DISPLAY INVISIBLE (-500 3725);
FORCEPROP 1 LAST PATH I250
J 2
(-173 3850);
DISPLAY 0.872340 (-173 3850);
PAINT GREEN (-173 3850);
DISPLAY INVISIBLE (-173 3850);
FORCEADD TAP..1
R 2
(-175 3800);
FORCEPROP 3 LASTPIN (-125 3800) SIG_NAME P5E_CPU1_PE2_RX_DP<14>
J 0
(-115 3810);
DISPLAY 0.659574 (-115 3810);
PAINT MONO (-115 3810);
DISPLAY INVISIBLE (-115 3810);
FORCEPROP 1 LASTPIN (-125 3800) BN 14
J 2
(-113 3808);
DISPLAY 0.680851 (-113 3808);
PAINT GREEN (-113 3808);
FORCEPROP 2 LAST CDS_LIB standard
J 0
(-175 3800);
DISPLAY INVISIBLE (-175 3800);
FORCEPROP 1 LAST BODY_TYPE PLUMBING
J 2
(-175 3850);
DISPLAY 0.872340 (-175 3850);
PAINT GREEN (-175 3850);
DISPLAY INVISIBLE (-175 3850);
FORCEPROP 1 LAST HDL_TAP TRUE
J 2
(-500 3675);
DISPLAY 0.872340 (-500 3675);
DISPLAY INVISIBLE (-500 3675);
FORCEPROP 1 LAST PATH I251
J 2
(-173 3800);
DISPLAY 0.872340 (-173 3800);
PAINT GREEN (-173 3800);
DISPLAY INVISIBLE (-173 3800);
FORCEADD TAP..1
R 2
(-175 2750);
FORCEPROP 3 LASTPIN (-125 2750) SIG_NAME P5E_CPU1_PE2_RX_DN<10>
J 0
(-115 2760);
DISPLAY 0.659574 (-115 2760);
PAINT MONO (-115 2760);
DISPLAY INVISIBLE (-115 2760);
FORCEPROP 1 LASTPIN (-125 2750) BN 10
J 2
(-113 2758);
DISPLAY 0.680851 (-113 2758);
PAINT GREEN (-113 2758);
FORCEPROP 2 LAST CDS_LIB standard
J 0
(-175 2750);
DISPLAY INVISIBLE (-175 2750);
FORCEPROP 1 LAST BODY_TYPE PLUMBING
J 2
(-175 2800);
DISPLAY 0.872340 (-175 2800);
PAINT GREEN (-175 2800);
DISPLAY INVISIBLE (-175 2800);
FORCEPROP 1 LAST HDL_TAP TRUE
J 2
(-500 2625);
DISPLAY 0.872340 (-500 2625);
DISPLAY INVISIBLE (-500 2625);
FORCEPROP 1 LAST PATH I252
J 2
(-173 2750);
DISPLAY 0.872340 (-173 2750);
PAINT GREEN (-173 2750);
DISPLAY INVISIBLE (-173 2750);
FORCEADD TAP..1
R 2
(-175 2800);
FORCEPROP 3 LASTPIN (-125 2800) SIG_NAME P5E_CPU1_PE2_RX_DN<11>
J 0
(-115 2810);
DISPLAY 0.659574 (-115 2810);
PAINT MONO (-115 2810);
DISPLAY INVISIBLE (-115 2810);
FORCEPROP 1 LASTPIN (-125 2800) BN 11
J 2
(-113 2808);
DISPLAY 0.680851 (-113 2808);
PAINT GREEN (-113 2808);
FORCEPROP 2 LAST CDS_LIB standard
J 0
(-175 2800);
DISPLAY INVISIBLE (-175 2800);
FORCEPROP 1 LAST BODY_TYPE PLUMBING
J 2
(-175 2850);
DISPLAY 0.872340 (-175 2850);
PAINT GREEN (-175 2850);
DISPLAY INVISIBLE (-175 2850);
FORCEPROP 1 LAST HDL_TAP TRUE
J 2
(-500 2675);
DISPLAY 0.872340 (-500 2675);
DISPLAY INVISIBLE (-500 2675);
FORCEPROP 1 LAST PATH I253
J 2
(-173 2800);
DISPLAY 0.872340 (-173 2800);
PAINT GREEN (-173 2800);
DISPLAY INVISIBLE (-173 2800);
FORCEADD TAP..1
R 2
(-175 2900);
FORCEPROP 3 LASTPIN (-125 2900) SIG_NAME P5E_CPU1_PE2_RX_DN<13>
J 0
(-115 2910);
DISPLAY 0.659574 (-115 2910);
PAINT MONO (-115 2910);
DISPLAY INVISIBLE (-115 2910);
FORCEPROP 1 LASTPIN (-125 2900) BN 13
J 2
(-113 2908);
DISPLAY 0.680851 (-113 2908);
PAINT GREEN (-113 2908);
FORCEPROP 2 LAST CDS_LIB standard
J 0
(-175 2900);
DISPLAY INVISIBLE (-175 2900);
FORCEPROP 1 LAST BODY_TYPE PLUMBING
J 2
(-175 2950);
DISPLAY 0.872340 (-175 2950);
PAINT GREEN (-175 2950);
DISPLAY INVISIBLE (-175 2950);
FORCEPROP 1 LAST HDL_TAP TRUE
J 2
(-500 2775);
DISPLAY 0.872340 (-500 2775);
DISPLAY INVISIBLE (-500 2775);
FORCEPROP 1 LAST PATH I254
J 2
(-173 2900);
DISPLAY 0.872340 (-173 2900);
PAINT GREEN (-173 2900);
DISPLAY INVISIBLE (-173 2900);
FORCEADD TAP..1
R 2
(-175 2950);
FORCEPROP 3 LASTPIN (-125 2950) SIG_NAME P5E_CPU1_PE2_RX_DN<14>
J 0
(-115 2960);
DISPLAY 0.659574 (-115 2960);
PAINT MONO (-115 2960);
DISPLAY INVISIBLE (-115 2960);
FORCEPROP 1 LASTPIN (-125 2950) BN 14
J 2
(-113 2958);
DISPLAY 0.680851 (-113 2958);
PAINT GREEN (-113 2958);
FORCEPROP 2 LAST CDS_LIB standard
J 0
(-175 2950);
DISPLAY INVISIBLE (-175 2950);
FORCEPROP 1 LAST BODY_TYPE PLUMBING
J 2
(-175 3000);
DISPLAY 0.872340 (-175 3000);
PAINT GREEN (-175 3000);
DISPLAY INVISIBLE (-175 3000);
FORCEPROP 1 LAST HDL_TAP TRUE
J 2
(-500 2825);
DISPLAY 0.872340 (-500 2825);
DISPLAY INVISIBLE (-500 2825);
FORCEPROP 1 LAST PATH I255
J 2
(-173 2950);
DISPLAY 0.872340 (-173 2950);
PAINT GREEN (-173 2950);
DISPLAY INVISIBLE (-173 2950);
FORCEADD TAP..1
R 2
(-175 3000);
FORCEPROP 3 LASTPIN (-125 3000) SIG_NAME P5E_CPU1_PE2_RX_DN<15>
J 0
(-115 3010);
DISPLAY 0.659574 (-115 3010);
PAINT MONO (-115 3010);
DISPLAY INVISIBLE (-115 3010);
FORCEPROP 1 LASTPIN (-125 3000) BN 15
J 2
(-113 3008);
DISPLAY 0.680851 (-113 3008);
PAINT GREEN (-113 3008);
FORCEPROP 2 LAST CDS_LIB standard
J 0
(-175 3000);
DISPLAY INVISIBLE (-175 3000);
FORCEPROP 1 LAST BODY_TYPE PLUMBING
J 2
(-175 3050);
DISPLAY 0.872340 (-175 3050);
PAINT GREEN (-175 3050);
DISPLAY INVISIBLE (-175 3050);
FORCEPROP 1 LAST HDL_TAP TRUE
J 2
(-500 2875);
DISPLAY 0.872340 (-500 2875);
DISPLAY INVISIBLE (-500 2875);
FORCEPROP 1 LAST PATH I256
J 2
(-173 3000);
DISPLAY 0.872340 (-173 3000);
PAINT GREEN (-173 3000);
DISPLAY INVISIBLE (-173 3000);
FORCEADD TAP..1
(3225 2350);
FORCEPROP 3 LASTPIN (3175 2350) SIG_NAME P5E_CPU1_PE2_TX_DN<2>
J 0
(3185 2360);
DISPLAY 0.659574 (3185 2360);
PAINT MONO (3185 2360);
DISPLAY INVISIBLE (3185 2360);
FORCEPROP 1 LASTPIN (3175 2350) BN 2
J 0
(3163 2358);
DISPLAY 0.680851 (3163 2358);
PAINT GREEN (3163 2358);
FORCEPROP 2 LAST CDS_LIB standard
J 0
(3225 2350);
PAINT MONO (3225 2350);
DISPLAY INVISIBLE (3225 2350);
FORCEPROP 1 LAST BODY_TYPE PLUMBING
J 0
(3225 2400);
DISPLAY 0.872340 (3225 2400);
PAINT GREEN (3225 2400);
DISPLAY INVISIBLE (3225 2400);
FORCEPROP 1 LAST HDL_TAP TRUE
J 0
(3550 2225);
DISPLAY 0.872340 (3550 2225);
DISPLAY INVISIBLE (3550 2225);
FORCEPROP 1 LAST PATH I257
J 0
(3223 2350);
DISPLAY 0.872340 (3223 2350);
PAINT GREEN (3223 2350);
DISPLAY INVISIBLE (3223 2350);
FORCEADD TAP..1
(3225 2300);
FORCEPROP 3 LASTPIN (3175 2300) SIG_NAME P5E_CPU1_PE2_TX_DN<1>
J 0
(3185 2310);
DISPLAY 0.659574 (3185 2310);
PAINT MONO (3185 2310);
DISPLAY INVISIBLE (3185 2310);
FORCEPROP 1 LASTPIN (3175 2300) BN 1
J 0
(3163 2308);
DISPLAY 0.680851 (3163 2308);
PAINT GREEN (3163 2308);
FORCEPROP 2 LAST CDS_LIB standard
J 0
(3225 2300);
PAINT MONO (3225 2300);
DISPLAY INVISIBLE (3225 2300);
FORCEPROP 1 LAST BODY_TYPE PLUMBING
J 0
(3225 2350);
DISPLAY 0.872340 (3225 2350);
PAINT GREEN (3225 2350);
DISPLAY INVISIBLE (3225 2350);
FORCEPROP 1 LAST HDL_TAP TRUE
J 0
(3550 2175);
DISPLAY 0.872340 (3550 2175);
DISPLAY INVISIBLE (3550 2175);
FORCEPROP 1 LAST PATH I258
J 0
(3223 2300);
DISPLAY 0.872340 (3223 2300);
PAINT GREEN (3223 2300);
DISPLAY INVISIBLE (3223 2300);
FORCEADD TAP..1
(3225 2250);
FORCEPROP 3 LASTPIN (3175 2250) SIG_NAME P5E_CPU1_PE2_TX_DN<0>
J 0
(3185 2260);
DISPLAY 0.659574 (3185 2260);
PAINT MONO (3185 2260);
DISPLAY INVISIBLE (3185 2260);
FORCEPROP 1 LASTPIN (3175 2250) BN 0
J 0
(3163 2258);
DISPLAY 0.680851 (3163 2258);
PAINT GREEN (3163 2258);
FORCEPROP 2 LAST CDS_LIB standard
J 0
(3225 2250);
PAINT MONO (3225 2250);
DISPLAY INVISIBLE (3225 2250);
FORCEPROP 1 LAST BODY_TYPE PLUMBING
J 0
(3225 2300);
DISPLAY 0.872340 (3225 2300);
PAINT GREEN (3225 2300);
DISPLAY INVISIBLE (3225 2300);
FORCEPROP 1 LAST HDL_TAP TRUE
J 0
(3550 2125);
DISPLAY 0.872340 (3550 2125);
DISPLAY INVISIBLE (3550 2125);
FORCEPROP 1 LAST PATH I259
J 0
(3223 2250);
DISPLAY 0.872340 (3223 2250);
PAINT GREEN (3223 2250);
DISPLAY INVISIBLE (3223 2250);
FORCEADD TAP..1
R 2
(-200 625);
FORCEPROP 3 LASTPIN (-150 625) SIG_NAME P5E_CPU1_PE3_RX_DP<6>
J 0
(-140 635);
DISPLAY 0.659574 (-140 635);
PAINT MONO (-140 635);
DISPLAY INVISIBLE (-140 635);
FORCEPROP 1 LASTPIN (-150 625) BN 6
J 2
(-138 633);
DISPLAY 0.680851 (-138 633);
PAINT GREEN (-138 633);
FORCEPROP 2 LAST CDS_LIB standard
J 0
(-200 625);
DISPLAY INVISIBLE (-200 625);
FORCEPROP 1 LAST BODY_TYPE PLUMBING
J 2
(-200 675);
DISPLAY 0.872340 (-200 675);
PAINT GREEN (-200 675);
DISPLAY INVISIBLE (-200 675);
FORCEPROP 1 LAST HDL_TAP TRUE
J 2
(-525 500);
DISPLAY 0.872340 (-525 500);
DISPLAY INVISIBLE (-525 500);
FORCEPROP 1 LAST PATH I26
J 2
(-198 625);
DISPLAY 0.872340 (-198 625);
PAINT GREEN (-198 625);
DISPLAY INVISIBLE (-198 625);
FORCEADD TAP..1
(3225 2450);
FORCEPROP 3 LASTPIN (3175 2450) SIG_NAME P5E_CPU1_PE2_TX_DN<4>
J 0
(3185 2460);
DISPLAY 0.659574 (3185 2460);
PAINT MONO (3185 2460);
DISPLAY INVISIBLE (3185 2460);
FORCEPROP 1 LASTPIN (3175 2450) BN 4
J 0
(3163 2458);
DISPLAY 0.680851 (3163 2458);
PAINT GREEN (3163 2458);
FORCEPROP 2 LAST CDS_LIB standard
J 0
(3225 2450);
PAINT MONO (3225 2450);
DISPLAY INVISIBLE (3225 2450);
FORCEPROP 1 LAST BODY_TYPE PLUMBING
J 0
(3225 2500);
DISPLAY 0.872340 (3225 2500);
PAINT GREEN (3225 2500);
DISPLAY INVISIBLE (3225 2500);
FORCEPROP 1 LAST HDL_TAP TRUE
J 0
(3550 2325);
DISPLAY 0.872340 (3550 2325);
DISPLAY INVISIBLE (3550 2325);
FORCEPROP 1 LAST PATH I260
J 0
(3223 2450);
DISPLAY 0.872340 (3223 2450);
PAINT GREEN (3223 2450);
DISPLAY INVISIBLE (3223 2450);
FORCEADD TAP..1
(3225 2400);
FORCEPROP 3 LASTPIN (3175 2400) SIG_NAME P5E_CPU1_PE2_TX_DN<3>
J 0
(3185 2410);
DISPLAY 0.659574 (3185 2410);
PAINT MONO (3185 2410);
DISPLAY INVISIBLE (3185 2410);
FORCEPROP 1 LASTPIN (3175 2400) BN 3
J 0
(3163 2408);
DISPLAY 0.680851 (3163 2408);
PAINT GREEN (3163 2408);
FORCEPROP 2 LAST CDS_LIB standard
J 0
(3225 2400);
PAINT MONO (3225 2400);
DISPLAY INVISIBLE (3225 2400);
FORCEPROP 1 LAST BODY_TYPE PLUMBING
J 0
(3225 2450);
DISPLAY 0.872340 (3225 2450);
PAINT GREEN (3225 2450);
DISPLAY INVISIBLE (3225 2450);
FORCEPROP 1 LAST HDL_TAP TRUE
J 0
(3550 2275);
DISPLAY 0.872340 (3550 2275);
DISPLAY INVISIBLE (3550 2275);
FORCEPROP 1 LAST PATH I261
J 0
(3223 2400);
DISPLAY 0.872340 (3223 2400);
PAINT GREEN (3223 2400);
DISPLAY INVISIBLE (3223 2400);
FORCEADD TAP..1
(3225 2600);
FORCEPROP 3 LASTPIN (3175 2600) SIG_NAME P5E_CPU1_PE2_TX_DN<7>
J 0
(3185 2610);
DISPLAY 0.659574 (3185 2610);
PAINT MONO (3185 2610);
DISPLAY INVISIBLE (3185 2610);
FORCEPROP 1 LASTPIN (3175 2600) BN 7
J 0
(3163 2608);
DISPLAY 0.680851 (3163 2608);
PAINT GREEN (3163 2608);
FORCEPROP 2 LAST CDS_LIB standard
J 0
(3225 2600);
PAINT MONO (3225 2600);
DISPLAY INVISIBLE (3225 2600);
FORCEPROP 1 LAST BODY_TYPE PLUMBING
J 0
(3225 2650);
DISPLAY 0.872340 (3225 2650);
PAINT GREEN (3225 2650);
DISPLAY INVISIBLE (3225 2650);
FORCEPROP 1 LAST HDL_TAP TRUE
J 0
(3550 2475);
DISPLAY 0.872340 (3550 2475);
DISPLAY INVISIBLE (3550 2475);
FORCEPROP 1 LAST PATH I262
J 0
(3223 2600);
DISPLAY 0.872340 (3223 2600);
PAINT GREEN (3223 2600);
DISPLAY INVISIBLE (3223 2600);
FORCEADD TAP..1
(3225 2550);
FORCEPROP 3 LASTPIN (3175 2550) SIG_NAME P5E_CPU1_PE2_TX_DN<6>
J 0
(3185 2560);
DISPLAY 0.659574 (3185 2560);
PAINT MONO (3185 2560);
DISPLAY INVISIBLE (3185 2560);
FORCEPROP 1 LASTPIN (3175 2550) BN 6
J 0
(3163 2558);
DISPLAY 0.680851 (3163 2558);
PAINT GREEN (3163 2558);
FORCEPROP 2 LAST CDS_LIB standard
J 0
(3225 2550);
PAINT MONO (3225 2550);
DISPLAY INVISIBLE (3225 2550);
FORCEPROP 1 LAST BODY_TYPE PLUMBING
J 0
(3225 2600);
DISPLAY 0.872340 (3225 2600);
PAINT GREEN (3225 2600);
DISPLAY INVISIBLE (3225 2600);
FORCEPROP 1 LAST HDL_TAP TRUE
J 0
(3550 2425);
DISPLAY 0.872340 (3550 2425);
DISPLAY INVISIBLE (3550 2425);
FORCEPROP 1 LAST PATH I263
J 0
(3223 2550);
DISPLAY 0.872340 (3223 2550);
PAINT GREEN (3223 2550);
DISPLAY INVISIBLE (3223 2550);
FORCEADD TAP..1
(3225 2500);
FORCEPROP 3 LASTPIN (3175 2500) SIG_NAME P5E_CPU1_PE2_TX_DN<5>
J 0
(3185 2510);
DISPLAY 0.659574 (3185 2510);
PAINT MONO (3185 2510);
DISPLAY INVISIBLE (3185 2510);
FORCEPROP 1 LASTPIN (3175 2500) BN 5
J 0
(3163 2508);
DISPLAY 0.680851 (3163 2508);
PAINT GREEN (3163 2508);
FORCEPROP 2 LAST CDS_LIB standard
J 0
(3225 2500);
PAINT MONO (3225 2500);
DISPLAY INVISIBLE (3225 2500);
FORCEPROP 1 LAST BODY_TYPE PLUMBING
J 0
(3225 2550);
DISPLAY 0.872340 (3225 2550);
PAINT GREEN (3225 2550);
DISPLAY INVISIBLE (3225 2550);
FORCEPROP 1 LAST HDL_TAP TRUE
J 0
(3550 2375);
DISPLAY 0.872340 (3550 2375);
DISPLAY INVISIBLE (3550 2375);
FORCEPROP 1 LAST PATH I264
J 0
(3223 2500);
DISPLAY 0.872340 (3223 2500);
PAINT GREEN (3223 2500);
DISPLAY INVISIBLE (3223 2500);
FORCEADD TAP..1
(3225 2650);
FORCEPROP 3 LASTPIN (3175 2650) SIG_NAME P5E_CPU1_PE2_TX_DN<8>
J 0
(3185 2660);
DISPLAY 0.659574 (3185 2660);
PAINT MONO (3185 2660);
DISPLAY INVISIBLE (3185 2660);
FORCEPROP 1 LASTPIN (3175 2650) BN 8
J 0
(3163 2658);
DISPLAY 0.680851 (3163 2658);
PAINT GREEN (3163 2658);
FORCEPROP 2 LAST CDS_LIB standard
J 0
(3225 2650);
PAINT MONO (3225 2650);
DISPLAY INVISIBLE (3225 2650);
FORCEPROP 1 LAST BODY_TYPE PLUMBING
J 0
(3225 2700);
DISPLAY 0.872340 (3225 2700);
PAINT GREEN (3225 2700);
DISPLAY INVISIBLE (3225 2700);
FORCEPROP 1 LAST HDL_TAP TRUE
J 0
(3550 2525);
DISPLAY 0.872340 (3550 2525);
DISPLAY INVISIBLE (3550 2525);
FORCEPROP 1 LAST PATH I265
J 0
(3223 2650);
DISPLAY 0.872340 (3223 2650);
PAINT GREEN (3223 2650);
DISPLAY INVISIBLE (3223 2650);
FORCEADD TAP..1
(3225 2700);
FORCEPROP 3 LASTPIN (3175 2700) SIG_NAME P5E_CPU1_PE2_TX_DN<9>
J 0
(3185 2710);
DISPLAY 0.659574 (3185 2710);
PAINT MONO (3185 2710);
DISPLAY INVISIBLE (3185 2710);
FORCEPROP 1 LASTPIN (3175 2700) BN 9
J 0
(3163 2708);
DISPLAY 0.680851 (3163 2708);
PAINT GREEN (3163 2708);
FORCEPROP 2 LAST CDS_LIB standard
J 0
(3225 2700);
DISPLAY INVISIBLE (3225 2700);
FORCEPROP 1 LAST BODY_TYPE PLUMBING
J 0
(3225 2750);
DISPLAY 0.872340 (3225 2750);
PAINT GREEN (3225 2750);
DISPLAY INVISIBLE (3225 2750);
FORCEPROP 1 LAST HDL_TAP TRUE
J 0
(3550 2575);
DISPLAY 0.872340 (3550 2575);
DISPLAY INVISIBLE (3550 2575);
FORCEPROP 1 LAST PATH I266
J 0
(3223 2700);
DISPLAY 0.872340 (3223 2700);
PAINT GREEN (3223 2700);
DISPLAY INVISIBLE (3223 2700);
FORCEADD TAP..1
(3225 2850);
FORCEPROP 3 LASTPIN (3175 2850) SIG_NAME P5E_CPU1_PE2_TX_DN<12>
J 0
(3185 2860);
DISPLAY 0.659574 (3185 2860);
PAINT MONO (3185 2860);
DISPLAY INVISIBLE (3185 2860);
FORCEPROP 1 LASTPIN (3175 2850) BN 12
J 0
(3163 2858);
DISPLAY 0.680851 (3163 2858);
PAINT GREEN (3163 2858);
FORCEPROP 2 LAST CDS_LIB standard
J 0
(3225 2850);
DISPLAY INVISIBLE (3225 2850);
FORCEPROP 1 LAST BODY_TYPE PLUMBING
J 0
(3225 2900);
DISPLAY 0.872340 (3225 2900);
PAINT GREEN (3225 2900);
DISPLAY INVISIBLE (3225 2900);
FORCEPROP 1 LAST HDL_TAP TRUE
J 0
(3550 2725);
DISPLAY 0.872340 (3550 2725);
DISPLAY INVISIBLE (3550 2725);
FORCEPROP 1 LAST PATH I267
J 0
(3223 2850);
DISPLAY 0.872340 (3223 2850);
PAINT GREEN (3223 2850);
DISPLAY INVISIBLE (3223 2850);
FORCEADD TAP..1
(3225 2750);
FORCEPROP 3 LASTPIN (3175 2750) SIG_NAME P5E_CPU1_PE2_TX_DN<10>
J 0
(3185 2760);
DISPLAY 0.659574 (3185 2760);
PAINT MONO (3185 2760);
DISPLAY INVISIBLE (3185 2760);
FORCEPROP 1 LASTPIN (3175 2750) BN 10
J 0
(3163 2758);
DISPLAY 0.680851 (3163 2758);
PAINT GREEN (3163 2758);
FORCEPROP 2 LAST CDS_LIB standard
J 0
(3225 2750);
DISPLAY INVISIBLE (3225 2750);
FORCEPROP 1 LAST BODY_TYPE PLUMBING
J 0
(3225 2800);
DISPLAY 0.872340 (3225 2800);
PAINT GREEN (3225 2800);
DISPLAY INVISIBLE (3225 2800);
FORCEPROP 1 LAST HDL_TAP TRUE
J 0
(3550 2625);
DISPLAY 0.872340 (3550 2625);
DISPLAY INVISIBLE (3550 2625);
FORCEPROP 1 LAST PATH I268
J 0
(3223 2750);
DISPLAY 0.872340 (3223 2750);
PAINT GREEN (3223 2750);
DISPLAY INVISIBLE (3223 2750);
FORCEADD TAP..1
(3225 2900);
FORCEPROP 3 LASTPIN (3175 2900) SIG_NAME P5E_CPU1_PE2_TX_DN<13>
J 0
(3185 2910);
DISPLAY 0.659574 (3185 2910);
PAINT MONO (3185 2910);
DISPLAY INVISIBLE (3185 2910);
FORCEPROP 1 LASTPIN (3175 2900) BN 13
J 0
(3163 2908);
DISPLAY 0.680851 (3163 2908);
PAINT GREEN (3163 2908);
FORCEPROP 2 LAST CDS_LIB standard
J 0
(3225 2900);
DISPLAY INVISIBLE (3225 2900);
FORCEPROP 1 LAST BODY_TYPE PLUMBING
J 0
(3225 2950);
DISPLAY 0.872340 (3225 2950);
PAINT GREEN (3225 2950);
DISPLAY INVISIBLE (3225 2950);
FORCEPROP 1 LAST HDL_TAP TRUE
J 0
(3550 2775);
DISPLAY 0.872340 (3550 2775);
DISPLAY INVISIBLE (3550 2775);
FORCEPROP 1 LAST PATH I269
J 0
(3223 2900);
DISPLAY 0.872340 (3223 2900);
PAINT GREEN (3223 2900);
DISPLAY INVISIBLE (3223 2900);
FORCEADD TAP..1
R 2
(-200 725);
FORCEPROP 3 LASTPIN (-150 725) SIG_NAME P5E_CPU1_PE3_RX_DP<8>
J 0
(-140 735);
DISPLAY 0.659574 (-140 735);
PAINT MONO (-140 735);
DISPLAY INVISIBLE (-140 735);
FORCEPROP 1 LASTPIN (-150 725) BN 8
J 2
(-138 733);
DISPLAY 0.680851 (-138 733);
PAINT GREEN (-138 733);
FORCEPROP 2 LAST CDS_LIB standard
J 0
(-200 725);
DISPLAY INVISIBLE (-200 725);
FORCEPROP 1 LAST BODY_TYPE PLUMBING
J 2
(-200 775);
DISPLAY 0.872340 (-200 775);
PAINT GREEN (-200 775);
DISPLAY INVISIBLE (-200 775);
FORCEPROP 1 LAST HDL_TAP TRUE
J 2
(-525 600);
DISPLAY 0.872340 (-525 600);
DISPLAY INVISIBLE (-525 600);
FORCEPROP 1 LAST PATH I27
J 2
(-198 725);
DISPLAY 0.872340 (-198 725);
PAINT GREEN (-198 725);
DISPLAY INVISIBLE (-198 725);
FORCEADD TAP..1
(3225 2950);
FORCEPROP 3 LASTPIN (3175 2950) SIG_NAME P5E_CPU1_PE2_TX_DN<14>
J 0
(3185 2960);
DISPLAY 0.659574 (3185 2960);
PAINT MONO (3185 2960);
DISPLAY INVISIBLE (3185 2960);
FORCEPROP 1 LASTPIN (3175 2950) BN 14
J 0
(3163 2958);
DISPLAY 0.680851 (3163 2958);
PAINT GREEN (3163 2958);
FORCEPROP 2 LAST CDS_LIB standard
J 0
(3225 2950);
DISPLAY INVISIBLE (3225 2950);
FORCEPROP 1 LAST BODY_TYPE PLUMBING
J 0
(3225 3000);
DISPLAY 0.872340 (3225 3000);
PAINT GREEN (3225 3000);
DISPLAY INVISIBLE (3225 3000);
FORCEPROP 1 LAST HDL_TAP TRUE
J 0
(3550 2825);
DISPLAY 0.872340 (3550 2825);
DISPLAY INVISIBLE (3550 2825);
FORCEPROP 1 LAST PATH I270
J 0
(3223 2950);
DISPLAY 0.872340 (3223 2950);
PAINT GREEN (3223 2950);
DISPLAY INVISIBLE (3223 2950);
FORCEADD TAP..1
(3225 3000);
FORCEPROP 3 LASTPIN (3175 3000) SIG_NAME P5E_CPU1_PE2_TX_DN<15>
J 0
(3185 3010);
DISPLAY 0.659574 (3185 3010);
PAINT MONO (3185 3010);
DISPLAY INVISIBLE (3185 3010);
FORCEPROP 1 LASTPIN (3175 3000) BN 15
J 0
(3163 3008);
DISPLAY 0.680851 (3163 3008);
PAINT GREEN (3163 3008);
FORCEPROP 2 LAST CDS_LIB standard
J 0
(3225 3000);
DISPLAY INVISIBLE (3225 3000);
FORCEPROP 1 LAST BODY_TYPE PLUMBING
J 0
(3225 3050);
DISPLAY 0.872340 (3225 3050);
PAINT GREEN (3225 3050);
DISPLAY INVISIBLE (3225 3050);
FORCEPROP 1 LAST HDL_TAP TRUE
J 0
(3550 2875);
DISPLAY 0.872340 (3550 2875);
DISPLAY INVISIBLE (3550 2875);
FORCEPROP 1 LAST PATH I271
J 0
(3223 3000);
DISPLAY 0.872340 (3223 3000);
PAINT GREEN (3223 3000);
DISPLAY INVISIBLE (3223 3000);
FORCEADD TAP..1
(3225 3100);
FORCEPROP 3 LASTPIN (3175 3100) SIG_NAME P5E_CPU1_PE2_TX_DP<0>
J 0
(3185 3110);
DISPLAY 0.659574 (3185 3110);
PAINT MONO (3185 3110);
DISPLAY INVISIBLE (3185 3110);
FORCEPROP 1 LASTPIN (3175 3100) BN 0
J 0
(3163 3108);
DISPLAY 0.680851 (3163 3108);
PAINT GREEN (3163 3108);
FORCEPROP 2 LAST CDS_LIB standard
J 0
(3225 3100);
PAINT MONO (3225 3100);
DISPLAY INVISIBLE (3225 3100);
FORCEPROP 1 LAST BODY_TYPE PLUMBING
J 0
(3225 3150);
DISPLAY 0.872340 (3225 3150);
PAINT GREEN (3225 3150);
DISPLAY INVISIBLE (3225 3150);
FORCEPROP 1 LAST HDL_TAP TRUE
J 0
(3550 2975);
DISPLAY 0.872340 (3550 2975);
DISPLAY INVISIBLE (3550 2975);
FORCEPROP 1 LAST PATH I272
J 0
(3223 3100);
DISPLAY 0.872340 (3223 3100);
PAINT GREEN (3223 3100);
DISPLAY INVISIBLE (3223 3100);
FORCEADD TAP..1
(3225 3250);
FORCEPROP 3 LASTPIN (3175 3250) SIG_NAME P5E_CPU1_PE2_TX_DP<3>
J 0
(3185 3260);
DISPLAY 0.659574 (3185 3260);
PAINT MONO (3185 3260);
DISPLAY INVISIBLE (3185 3260);
FORCEPROP 1 LASTPIN (3175 3250) BN 3
J 0
(3163 3258);
DISPLAY 0.680851 (3163 3258);
PAINT GREEN (3163 3258);
FORCEPROP 2 LAST CDS_LIB standard
J 0
(3225 3250);
PAINT MONO (3225 3250);
DISPLAY INVISIBLE (3225 3250);
FORCEPROP 1 LAST BODY_TYPE PLUMBING
J 0
(3225 3300);
DISPLAY 0.872340 (3225 3300);
PAINT GREEN (3225 3300);
DISPLAY INVISIBLE (3225 3300);
FORCEPROP 1 LAST HDL_TAP TRUE
J 0
(3550 3125);
DISPLAY 0.872340 (3550 3125);
DISPLAY INVISIBLE (3550 3125);
FORCEPROP 1 LAST PATH I273
J 0
(3223 3250);
DISPLAY 0.872340 (3223 3250);
PAINT GREEN (3223 3250);
DISPLAY INVISIBLE (3223 3250);
FORCEADD TAP..1
(3225 3150);
FORCEPROP 3 LASTPIN (3175 3150) SIG_NAME P5E_CPU1_PE2_TX_DP<1>
J 0
(3185 3160);
DISPLAY 0.659574 (3185 3160);
PAINT MONO (3185 3160);
DISPLAY INVISIBLE (3185 3160);
FORCEPROP 1 LASTPIN (3175 3150) BN 1
J 0
(3163 3158);
DISPLAY 0.680851 (3163 3158);
PAINT GREEN (3163 3158);
FORCEPROP 2 LAST CDS_LIB standard
J 0
(3225 3150);
PAINT MONO (3225 3150);
DISPLAY INVISIBLE (3225 3150);
FORCEPROP 1 LAST BODY_TYPE PLUMBING
J 0
(3225 3200);
DISPLAY 0.872340 (3225 3200);
PAINT GREEN (3225 3200);
DISPLAY INVISIBLE (3225 3200);
FORCEPROP 1 LAST HDL_TAP TRUE
J 0
(3550 3025);
DISPLAY 0.872340 (3550 3025);
DISPLAY INVISIBLE (3550 3025);
FORCEPROP 1 LAST PATH I274
J 0
(3223 3150);
DISPLAY 0.872340 (3223 3150);
PAINT GREEN (3223 3150);
DISPLAY INVISIBLE (3223 3150);
FORCEADD TAP..1
(3225 3200);
FORCEPROP 3 LASTPIN (3175 3200) SIG_NAME P5E_CPU1_PE2_TX_DP<2>
J 0
(3185 3210);
DISPLAY 0.659574 (3185 3210);
PAINT MONO (3185 3210);
DISPLAY INVISIBLE (3185 3210);
FORCEPROP 1 LASTPIN (3175 3200) BN 2
J 0
(3163 3208);
DISPLAY 0.680851 (3163 3208);
PAINT GREEN (3163 3208);
FORCEPROP 2 LAST CDS_LIB standard
J 0
(3225 3200);
PAINT MONO (3225 3200);
DISPLAY INVISIBLE (3225 3200);
FORCEPROP 1 LAST BODY_TYPE PLUMBING
J 0
(3225 3250);
DISPLAY 0.872340 (3225 3250);
PAINT GREEN (3225 3250);
DISPLAY INVISIBLE (3225 3250);
FORCEPROP 1 LAST HDL_TAP TRUE
J 0
(3550 3075);
DISPLAY 0.872340 (3550 3075);
DISPLAY INVISIBLE (3550 3075);
FORCEPROP 1 LAST PATH I275
J 0
(3223 3200);
DISPLAY 0.872340 (3223 3200);
PAINT GREEN (3223 3200);
DISPLAY INVISIBLE (3223 3200);
FORCEADD TAP..1
(3225 3350);
FORCEPROP 3 LASTPIN (3175 3350) SIG_NAME P5E_CPU1_PE2_TX_DP<5>
J 0
(3185 3360);
DISPLAY 0.659574 (3185 3360);
PAINT MONO (3185 3360);
DISPLAY INVISIBLE (3185 3360);
FORCEPROP 1 LASTPIN (3175 3350) BN 5
J 0
(3163 3358);
DISPLAY 0.680851 (3163 3358);
PAINT GREEN (3163 3358);
FORCEPROP 2 LAST CDS_LIB standard
J 0
(3225 3350);
PAINT MONO (3225 3350);
DISPLAY INVISIBLE (3225 3350);
FORCEPROP 1 LAST BODY_TYPE PLUMBING
J 0
(3225 3400);
DISPLAY 0.872340 (3225 3400);
PAINT GREEN (3225 3400);
DISPLAY INVISIBLE (3225 3400);
FORCEPROP 1 LAST HDL_TAP TRUE
J 0
(3550 3225);
DISPLAY 0.872340 (3550 3225);
DISPLAY INVISIBLE (3550 3225);
FORCEPROP 1 LAST PATH I276
J 0
(3223 3350);
DISPLAY 0.872340 (3223 3350);
PAINT GREEN (3223 3350);
DISPLAY INVISIBLE (3223 3350);
FORCEADD TAP..1
(3225 3300);
FORCEPROP 3 LASTPIN (3175 3300) SIG_NAME P5E_CPU1_PE2_TX_DP<4>
J 0
(3185 3310);
DISPLAY 0.659574 (3185 3310);
PAINT MONO (3185 3310);
DISPLAY INVISIBLE (3185 3310);
FORCEPROP 1 LASTPIN (3175 3300) BN 4
J 0
(3163 3308);
DISPLAY 0.680851 (3163 3308);
PAINT GREEN (3163 3308);
FORCEPROP 2 LAST CDS_LIB standard
J 0
(3225 3300);
PAINT MONO (3225 3300);
DISPLAY INVISIBLE (3225 3300);
FORCEPROP 1 LAST BODY_TYPE PLUMBING
J 0
(3225 3350);
DISPLAY 0.872340 (3225 3350);
PAINT GREEN (3225 3350);
DISPLAY INVISIBLE (3225 3350);
FORCEPROP 1 LAST HDL_TAP TRUE
J 0
(3550 3175);
DISPLAY 0.872340 (3550 3175);
DISPLAY INVISIBLE (3550 3175);
FORCEPROP 1 LAST PATH I277
J 0
(3223 3300);
DISPLAY 0.872340 (3223 3300);
PAINT GREEN (3223 3300);
DISPLAY INVISIBLE (3223 3300);
FORCEADD TAP..1
(3225 3500);
FORCEPROP 3 LASTPIN (3175 3500) SIG_NAME P5E_CPU1_PE2_TX_DP<8>
J 0
(3185 3510);
DISPLAY 0.659574 (3185 3510);
PAINT MONO (3185 3510);
DISPLAY INVISIBLE (3185 3510);
FORCEPROP 1 LASTPIN (3175 3500) BN 8
J 0
(3163 3508);
DISPLAY 0.680851 (3163 3508);
PAINT GREEN (3163 3508);
FORCEPROP 2 LAST CDS_LIB standard
J 0
(3225 3500);
PAINT MONO (3225 3500);
DISPLAY INVISIBLE (3225 3500);
FORCEPROP 1 LAST BODY_TYPE PLUMBING
J 0
(3225 3550);
DISPLAY 0.872340 (3225 3550);
PAINT GREEN (3225 3550);
DISPLAY INVISIBLE (3225 3550);
FORCEPROP 1 LAST HDL_TAP TRUE
J 0
(3550 3375);
DISPLAY 0.872340 (3550 3375);
DISPLAY INVISIBLE (3550 3375);
FORCEPROP 1 LAST PATH I278
J 0
(3223 3500);
DISPLAY 0.872340 (3223 3500);
PAINT GREEN (3223 3500);
DISPLAY INVISIBLE (3223 3500);
FORCEADD TAP..1
(3225 3400);
FORCEPROP 3 LASTPIN (3175 3400) SIG_NAME P5E_CPU1_PE2_TX_DP<6>
J 0
(3185 3410);
DISPLAY 0.659574 (3185 3410);
PAINT MONO (3185 3410);
DISPLAY INVISIBLE (3185 3410);
FORCEPROP 1 LASTPIN (3175 3400) BN 6
J 0
(3163 3408);
DISPLAY 0.680851 (3163 3408);
PAINT GREEN (3163 3408);
FORCEPROP 2 LAST CDS_LIB standard
J 0
(3225 3400);
PAINT MONO (3225 3400);
DISPLAY INVISIBLE (3225 3400);
FORCEPROP 1 LAST BODY_TYPE PLUMBING
J 0
(3225 3450);
DISPLAY 0.872340 (3225 3450);
PAINT GREEN (3225 3450);
DISPLAY INVISIBLE (3225 3450);
FORCEPROP 1 LAST HDL_TAP TRUE
J 0
(3550 3275);
DISPLAY 0.872340 (3550 3275);
DISPLAY INVISIBLE (3550 3275);
FORCEPROP 1 LAST PATH I279
J 0
(3223 3400);
DISPLAY 0.872340 (3223 3400);
PAINT GREEN (3223 3400);
DISPLAY INVISIBLE (3223 3400);
FORCEADD TAP..1
R 2
(-200 675);
FORCEPROP 3 LASTPIN (-150 675) SIG_NAME P5E_CPU1_PE3_RX_DP<7>
J 0
(-140 685);
DISPLAY 0.659574 (-140 685);
PAINT MONO (-140 685);
DISPLAY INVISIBLE (-140 685);
FORCEPROP 1 LASTPIN (-150 675) BN 7
J 2
(-138 683);
DISPLAY 0.680851 (-138 683);
PAINT GREEN (-138 683);
FORCEPROP 2 LAST CDS_LIB standard
J 0
(-200 675);
DISPLAY INVISIBLE (-200 675);
FORCEPROP 1 LAST BODY_TYPE PLUMBING
J 2
(-200 725);
DISPLAY 0.872340 (-200 725);
PAINT GREEN (-200 725);
DISPLAY INVISIBLE (-200 725);
FORCEPROP 1 LAST HDL_TAP TRUE
J 2
(-525 550);
DISPLAY 0.872340 (-525 550);
DISPLAY INVISIBLE (-525 550);
FORCEPROP 1 LAST PATH I28
J 2
(-198 675);
DISPLAY 0.872340 (-198 675);
PAINT GREEN (-198 675);
DISPLAY INVISIBLE (-198 675);
FORCEADD TAP..1
(3225 3450);
FORCEPROP 3 LASTPIN (3175 3450) SIG_NAME P5E_CPU1_PE2_TX_DP<7>
J 0
(3185 3460);
DISPLAY 0.659574 (3185 3460);
PAINT MONO (3185 3460);
DISPLAY INVISIBLE (3185 3460);
FORCEPROP 1 LASTPIN (3175 3450) BN 7
J 0
(3163 3458);
DISPLAY 0.680851 (3163 3458);
PAINT GREEN (3163 3458);
FORCEPROP 2 LAST CDS_LIB standard
J 0
(3225 3450);
PAINT MONO (3225 3450);
DISPLAY INVISIBLE (3225 3450);
FORCEPROP 1 LAST BODY_TYPE PLUMBING
J 0
(3225 3500);
DISPLAY 0.872340 (3225 3500);
PAINT GREEN (3225 3500);
DISPLAY INVISIBLE (3225 3500);
FORCEPROP 1 LAST HDL_TAP TRUE
J 0
(3550 3325);
DISPLAY 0.872340 (3550 3325);
DISPLAY INVISIBLE (3550 3325);
FORCEPROP 1 LAST PATH I280
J 0
(3223 3450);
DISPLAY 0.872340 (3223 3450);
PAINT GREEN (3223 3450);
DISPLAY INVISIBLE (3223 3450);
FORCEADD TAP..1
(3225 3600);
FORCEPROP 3 LASTPIN (3175 3600) SIG_NAME P5E_CPU1_PE2_TX_DP<10>
J 0
(3185 3610);
DISPLAY 0.659574 (3185 3610);
PAINT MONO (3185 3610);
DISPLAY INVISIBLE (3185 3610);
FORCEPROP 1 LASTPIN (3175 3600) BN 10
J 0
(3163 3608);
DISPLAY 0.680851 (3163 3608);
PAINT GREEN (3163 3608);
FORCEPROP 2 LAST CDS_LIB standard
J 0
(3225 3600);
DISPLAY INVISIBLE (3225 3600);
FORCEPROP 1 LAST BODY_TYPE PLUMBING
J 0
(3225 3650);
DISPLAY 0.872340 (3225 3650);
PAINT GREEN (3225 3650);
DISPLAY INVISIBLE (3225 3650);
FORCEPROP 1 LAST HDL_TAP TRUE
J 0
(3550 3475);
DISPLAY 0.872340 (3550 3475);
DISPLAY INVISIBLE (3550 3475);
FORCEPROP 1 LAST PATH I281
J 0
(3223 3600);
DISPLAY 0.872340 (3223 3600);
PAINT GREEN (3223 3600);
DISPLAY INVISIBLE (3223 3600);
FORCEADD TAP..1
(3225 3550);
FORCEPROP 3 LASTPIN (3175 3550) SIG_NAME P5E_CPU1_PE2_TX_DP<9>
J 0
(3185 3560);
DISPLAY 0.659574 (3185 3560);
PAINT MONO (3185 3560);
DISPLAY INVISIBLE (3185 3560);
FORCEPROP 1 LASTPIN (3175 3550) BN 9
J 0
(3163 3558);
DISPLAY 0.680851 (3163 3558);
PAINT GREEN (3163 3558);
FORCEPROP 2 LAST CDS_LIB standard
J 0
(3225 3550);
DISPLAY INVISIBLE (3225 3550);
FORCEPROP 1 LAST BODY_TYPE PLUMBING
J 0
(3225 3600);
DISPLAY 0.872340 (3225 3600);
PAINT GREEN (3225 3600);
DISPLAY INVISIBLE (3225 3600);
FORCEPROP 1 LAST HDL_TAP TRUE
J 0
(3550 3425);
DISPLAY 0.872340 (3550 3425);
DISPLAY INVISIBLE (3550 3425);
FORCEPROP 1 LAST PATH I282
J 0
(3223 3550);
DISPLAY 0.872340 (3223 3550);
PAINT GREEN (3223 3550);
DISPLAY INVISIBLE (3223 3550);
FORCEADD TAP..1
(3225 3750);
FORCEPROP 3 LASTPIN (3175 3750) SIG_NAME P5E_CPU1_PE2_TX_DP<13>
J 0
(3185 3760);
DISPLAY 0.659574 (3185 3760);
PAINT MONO (3185 3760);
DISPLAY INVISIBLE (3185 3760);
FORCEPROP 1 LASTPIN (3175 3750) BN 13
J 0
(3163 3758);
DISPLAY 0.680851 (3163 3758);
PAINT GREEN (3163 3758);
FORCEPROP 2 LAST CDS_LIB standard
J 0
(3225 3750);
DISPLAY INVISIBLE (3225 3750);
FORCEPROP 1 LAST BODY_TYPE PLUMBING
J 0
(3225 3800);
DISPLAY 0.872340 (3225 3800);
PAINT GREEN (3225 3800);
DISPLAY INVISIBLE (3225 3800);
FORCEPROP 1 LAST HDL_TAP TRUE
J 0
(3550 3625);
DISPLAY 0.872340 (3550 3625);
DISPLAY INVISIBLE (3550 3625);
FORCEPROP 1 LAST PATH I283
J 0
(3223 3750);
DISPLAY 0.872340 (3223 3750);
PAINT GREEN (3223 3750);
DISPLAY INVISIBLE (3223 3750);
FORCEADD TAP..1
(3225 3700);
FORCEPROP 3 LASTPIN (3175 3700) SIG_NAME P5E_CPU1_PE2_TX_DP<12>
J 0
(3185 3710);
DISPLAY 0.659574 (3185 3710);
PAINT MONO (3185 3710);
DISPLAY INVISIBLE (3185 3710);
FORCEPROP 1 LASTPIN (3175 3700) BN 12
J 0
(3163 3708);
DISPLAY 0.680851 (3163 3708);
PAINT GREEN (3163 3708);
FORCEPROP 2 LAST CDS_LIB standard
J 0
(3225 3700);
DISPLAY INVISIBLE (3225 3700);
FORCEPROP 1 LAST BODY_TYPE PLUMBING
J 0
(3225 3750);
DISPLAY 0.872340 (3225 3750);
PAINT GREEN (3225 3750);
DISPLAY INVISIBLE (3225 3750);
FORCEPROP 1 LAST HDL_TAP TRUE
J 0
(3550 3575);
DISPLAY 0.872340 (3550 3575);
DISPLAY INVISIBLE (3550 3575);
FORCEPROP 1 LAST PATH I284
J 0
(3223 3700);
DISPLAY 0.872340 (3223 3700);
PAINT GREEN (3223 3700);
DISPLAY INVISIBLE (3223 3700);
FORCEADD TAP..1
(3225 3650);
FORCEPROP 3 LASTPIN (3175 3650) SIG_NAME P5E_CPU1_PE2_TX_DP<11>
J 0
(3185 3660);
DISPLAY 0.659574 (3185 3660);
PAINT MONO (3185 3660);
DISPLAY INVISIBLE (3185 3660);
FORCEPROP 1 LASTPIN (3175 3650) BN 11
J 0
(3163 3658);
DISPLAY 0.680851 (3163 3658);
PAINT GREEN (3163 3658);
FORCEPROP 2 LAST CDS_LIB standard
J 0
(3225 3650);
DISPLAY INVISIBLE (3225 3650);
FORCEPROP 1 LAST BODY_TYPE PLUMBING
J 0
(3225 3700);
DISPLAY 0.872340 (3225 3700);
PAINT GREEN (3225 3700);
DISPLAY INVISIBLE (3225 3700);
FORCEPROP 1 LAST HDL_TAP TRUE
J 0
(3550 3525);
DISPLAY 0.872340 (3550 3525);
DISPLAY INVISIBLE (3550 3525);
FORCEPROP 1 LAST PATH I285
J 0
(3223 3650);
DISPLAY 0.872340 (3223 3650);
PAINT GREEN (3223 3650);
DISPLAY INVISIBLE (3223 3650);
FORCEADD TAP..1
(3225 3850);
FORCEPROP 3 LASTPIN (3175 3850) SIG_NAME P5E_CPU1_PE2_TX_DP<15>
J 0
(3185 3860);
DISPLAY 0.659574 (3185 3860);
PAINT MONO (3185 3860);
DISPLAY INVISIBLE (3185 3860);
FORCEPROP 1 LASTPIN (3175 3850) BN 15
J 0
(3163 3858);
DISPLAY 0.680851 (3163 3858);
PAINT GREEN (3163 3858);
FORCEPROP 2 LAST CDS_LIB standard
J 0
(3225 3850);
DISPLAY INVISIBLE (3225 3850);
FORCEPROP 1 LAST BODY_TYPE PLUMBING
J 0
(3225 3900);
DISPLAY 0.872340 (3225 3900);
PAINT GREEN (3225 3900);
DISPLAY INVISIBLE (3225 3900);
FORCEPROP 1 LAST HDL_TAP TRUE
J 0
(3550 3725);
DISPLAY 0.872340 (3550 3725);
DISPLAY INVISIBLE (3550 3725);
FORCEPROP 1 LAST PATH I286
J 0
(3223 3850);
DISPLAY 0.872340 (3223 3850);
PAINT GREEN (3223 3850);
DISPLAY INVISIBLE (3223 3850);
FORCEADD TAP..1
(3225 3800);
FORCEPROP 3 LASTPIN (3175 3800) SIG_NAME P5E_CPU1_PE2_TX_DP<14>
J 0
(3185 3810);
DISPLAY 0.659574 (3185 3810);
PAINT MONO (3185 3810);
DISPLAY INVISIBLE (3185 3810);
FORCEPROP 1 LASTPIN (3175 3800) BN 14
J 0
(3163 3808);
DISPLAY 0.680851 (3163 3808);
PAINT GREEN (3163 3808);
FORCEPROP 2 LAST CDS_LIB standard
J 0
(3225 3800);
DISPLAY INVISIBLE (3225 3800);
FORCEPROP 1 LAST BODY_TYPE PLUMBING
J 0
(3225 3850);
DISPLAY 0.872340 (3225 3850);
PAINT GREEN (3225 3850);
DISPLAY INVISIBLE (3225 3850);
FORCEPROP 1 LAST HDL_TAP TRUE
J 0
(3550 3675);
DISPLAY 0.872340 (3550 3675);
DISPLAY INVISIBLE (3550 3675);
FORCEPROP 1 LAST PATH I287
J 0
(3223 3800);
DISPLAY 0.872340 (3223 3800);
PAINT GREEN (3223 3800);
DISPLAY INVISIBLE (3223 3800);
FORCEADD OFFPAGE..2
(4325 3025);
FORCEPROP 2 LAST $XR0 176 
J 0
(4514 3025);
DISPLAY 0.638298 (4514 3025);
PAINT MONO (4514 3025);
FORCEPROP 2 LAST CDS_LIB standard
J 0
(4325 3025);
PAINT MONO (4325 3025);
DISPLAY INVISIBLE (4325 3025);
FORCEPROP 1 LAST OFFPAGE TRUE
J 0
(4650 2900);
DISPLAY 1.170213 (4650 2900);
PAINT GREEN (4650 2900);
DISPLAY INVISIBLE (4650 2900);
FORCEPROP 1 LAST COMMENT_BODY TRUE
J 0
(4280 2930);
DISPLAY 1.170213 (4280 2930);
PAINT GREEN (4280 2930);
DISPLAY INVISIBLE (4280 2930);
FORCEPROP 2 LAST PATH I288
J 0
(4525 3075);
DISPLAY 1.021277 (4525 3075);
DISPLAY INVISIBLE (4525 3075);
FORCEADD OFFPAGE..2
(4325 3875);
FORCEPROP 2 LAST $XR0 176 
J 0
(4514 3875);
DISPLAY 0.638298 (4514 3875);
PAINT MONO (4514 3875);
FORCEPROP 2 LAST CDS_LIB standard
J 0
(4325 3875);
PAINT MONO (4325 3875);
DISPLAY INVISIBLE (4325 3875);
FORCEPROP 1 LAST OFFPAGE TRUE
J 0
(4650 3750);
DISPLAY 1.170213 (4650 3750);
PAINT GREEN (4650 3750);
DISPLAY INVISIBLE (4650 3750);
FORCEPROP 1 LAST COMMENT_BODY TRUE
J 0
(4280 3780);
DISPLAY 1.170213 (4280 3780);
PAINT GREEN (4280 3780);
DISPLAY INVISIBLE (4280 3780);
FORCEPROP 2 LAST PATH I289
J 0
(4525 3925);
DISPLAY 1.021277 (4525 3925);
DISPLAY INVISIBLE (4525 3925);
FORCEADD TAP..1
R 2
(-200 775);
FORCEPROP 3 LASTPIN (-150 775) SIG_NAME P5E_CPU1_PE3_RX_DP<9>
J 0
(-140 785);
DISPLAY 0.659574 (-140 785);
PAINT MONO (-140 785);
DISPLAY INVISIBLE (-140 785);
FORCEPROP 1 LASTPIN (-150 775) BN 9
J 2
(-138 783);
DISPLAY 0.680851 (-138 783);
PAINT GREEN (-138 783);
FORCEPROP 2 LAST CDS_LIB standard
J 0
(-200 775);
DISPLAY INVISIBLE (-200 775);
FORCEPROP 1 LAST BODY_TYPE PLUMBING
J 2
(-200 825);
DISPLAY 0.872340 (-200 825);
PAINT GREEN (-200 825);
DISPLAY INVISIBLE (-200 825);
FORCEPROP 1 LAST HDL_TAP TRUE
J 2
(-525 650);
DISPLAY 0.872340 (-525 650);
DISPLAY INVISIBLE (-525 650);
FORCEPROP 1 LAST PATH I29
J 2
(-198 775);
DISPLAY 0.872340 (-198 775);
PAINT GREEN (-198 775);
DISPLAY INVISIBLE (-198 775);
FORCEADD TAP..1
(3225 2800);
FORCEPROP 3 LASTPIN (3175 2800) SIG_NAME P5E_CPU1_PE2_TX_DN<11>
J 0
(3185 2810);
DISPLAY 0.659574 (3185 2810);
PAINT MONO (3185 2810);
DISPLAY INVISIBLE (3185 2810);
FORCEPROP 1 LASTPIN (3175 2800) BN 11
J 0
(3163 2808);
DISPLAY 0.680851 (3163 2808);
PAINT GREEN (3163 2808);
FORCEPROP 2 LAST CDS_LIB standard
J 0
(3225 2800);
DISPLAY INVISIBLE (3225 2800);
FORCEPROP 1 LAST BODY_TYPE PLUMBING
J 0
(3225 2850);
DISPLAY 0.872340 (3225 2850);
PAINT GREEN (3225 2850);
DISPLAY INVISIBLE (3225 2850);
FORCEPROP 1 LAST HDL_TAP TRUE
J 0
(3550 2675);
DISPLAY 0.872340 (3550 2675);
DISPLAY INVISIBLE (3550 2675);
FORCEPROP 1 LAST PATH I290
J 0
(3223 2800);
DISPLAY 0.872340 (3223 2800);
PAINT GREEN (3223 2800);
DISPLAY INVISIBLE (3223 2800);
FORCEADD TAP..1
R 2
(-200 -425);
FORCEPROP 3 LASTPIN (-150 -425) SIG_NAME P5E_CPU1_PE3_RX_DN<2>
J 0
(-140 -415);
DISPLAY 0.659574 (-140 -415);
PAINT MONO (-140 -415);
DISPLAY INVISIBLE (-140 -415);
FORCEPROP 1 LASTPIN (-150 -425) BN 2
J 2
(-138 -417);
DISPLAY 0.680851 (-138 -417);
PAINT GREEN (-138 -417);
FORCEPROP 2 LAST CDS_LIB standard
J 0
(-200 -425);
DISPLAY INVISIBLE (-200 -425);
FORCEPROP 1 LAST BODY_TYPE PLUMBING
J 2
(-200 -375);
DISPLAY 0.872340 (-200 -375);
PAINT GREEN (-200 -375);
DISPLAY INVISIBLE (-200 -375);
FORCEPROP 1 LAST HDL_TAP TRUE
J 2
(-525 -550);
DISPLAY 0.872340 (-525 -550);
DISPLAY INVISIBLE (-525 -550);
FORCEPROP 1 LAST PATH I3
J 2
(-198 -425);
DISPLAY 0.872340 (-198 -425);
PAINT GREEN (-198 -425);
DISPLAY INVISIBLE (-198 -425);
FORCEADD TAP..1
R 2
(-200 825);
FORCEPROP 3 LASTPIN (-150 825) SIG_NAME P5E_CPU1_PE3_RX_DP<10>
J 0
(-140 835);
DISPLAY 0.659574 (-140 835);
PAINT MONO (-140 835);
DISPLAY INVISIBLE (-140 835);
FORCEPROP 1 LASTPIN (-150 825) BN 10
J 2
(-138 833);
DISPLAY 0.680851 (-138 833);
PAINT GREEN (-138 833);
FORCEPROP 2 LAST CDS_LIB standard
J 0
(-200 825);
DISPLAY INVISIBLE (-200 825);
FORCEPROP 1 LAST BODY_TYPE PLUMBING
J 2
(-200 875);
DISPLAY 0.872340 (-200 875);
PAINT GREEN (-200 875);
DISPLAY INVISIBLE (-200 875);
FORCEPROP 1 LAST HDL_TAP TRUE
J 2
(-525 700);
DISPLAY 0.872340 (-525 700);
DISPLAY INVISIBLE (-525 700);
FORCEPROP 1 LAST PATH I30
J 2
(-198 825);
DISPLAY 0.872340 (-198 825);
PAINT GREEN (-198 825);
DISPLAY INVISIBLE (-198 825);
FORCEADD TAP..1
R 2
(-200 875);
FORCEPROP 3 LASTPIN (-150 875) SIG_NAME P5E_CPU1_PE3_RX_DP<11>
J 0
(-140 885);
DISPLAY 0.659574 (-140 885);
PAINT MONO (-140 885);
DISPLAY INVISIBLE (-140 885);
FORCEPROP 1 LASTPIN (-150 875) BN 11
J 2
(-138 883);
DISPLAY 0.680851 (-138 883);
PAINT GREEN (-138 883);
FORCEPROP 2 LAST CDS_LIB standard
J 0
(-200 875);
DISPLAY INVISIBLE (-200 875);
FORCEPROP 1 LAST BODY_TYPE PLUMBING
J 2
(-200 925);
DISPLAY 0.872340 (-200 925);
PAINT GREEN (-200 925);
DISPLAY INVISIBLE (-200 925);
FORCEPROP 1 LAST HDL_TAP TRUE
J 2
(-525 750);
DISPLAY 0.872340 (-525 750);
DISPLAY INVISIBLE (-525 750);
FORCEPROP 1 LAST PATH I31
J 2
(-198 875);
DISPLAY 0.872340 (-198 875);
PAINT GREEN (-198 875);
DISPLAY INVISIBLE (-198 875);
FORCEADD TAP..1
R 2
(-200 925);
FORCEPROP 3 LASTPIN (-150 925) SIG_NAME P5E_CPU1_PE3_RX_DP<12>
J 0
(-140 935);
DISPLAY 0.659574 (-140 935);
PAINT MONO (-140 935);
DISPLAY INVISIBLE (-140 935);
FORCEPROP 1 LASTPIN (-150 925) BN 12
J 2
(-138 933);
DISPLAY 0.680851 (-138 933);
PAINT GREEN (-138 933);
FORCEPROP 2 LAST CDS_LIB standard
J 0
(-200 925);
DISPLAY INVISIBLE (-200 925);
FORCEPROP 1 LAST BODY_TYPE PLUMBING
J 2
(-200 975);
DISPLAY 0.872340 (-200 975);
PAINT GREEN (-200 975);
DISPLAY INVISIBLE (-200 975);
FORCEPROP 1 LAST HDL_TAP TRUE
J 2
(-525 800);
DISPLAY 0.872340 (-525 800);
DISPLAY INVISIBLE (-525 800);
FORCEPROP 1 LAST PATH I32
J 2
(-198 925);
DISPLAY 0.872340 (-198 925);
PAINT GREEN (-198 925);
DISPLAY INVISIBLE (-198 925);
FORCEADD TAP..1
R 2
(-200 975);
FORCEPROP 3 LASTPIN (-150 975) SIG_NAME P5E_CPU1_PE3_RX_DP<13>
J 0
(-140 985);
DISPLAY 0.659574 (-140 985);
PAINT MONO (-140 985);
DISPLAY INVISIBLE (-140 985);
FORCEPROP 1 LASTPIN (-150 975) BN 13
J 2
(-138 983);
DISPLAY 0.680851 (-138 983);
PAINT GREEN (-138 983);
FORCEPROP 2 LAST CDS_LIB standard
J 0
(-200 975);
DISPLAY INVISIBLE (-200 975);
FORCEPROP 1 LAST BODY_TYPE PLUMBING
J 2
(-200 1025);
DISPLAY 0.872340 (-200 1025);
PAINT GREEN (-200 1025);
DISPLAY INVISIBLE (-200 1025);
FORCEPROP 1 LAST HDL_TAP TRUE
J 2
(-525 850);
DISPLAY 0.872340 (-525 850);
DISPLAY INVISIBLE (-525 850);
FORCEPROP 1 LAST PATH I33
J 2
(-198 975);
DISPLAY 0.872340 (-198 975);
PAINT GREEN (-198 975);
DISPLAY INVISIBLE (-198 975);
FORCEADD TAP..1
R 2
(-200 1025);
FORCEPROP 3 LASTPIN (-150 1025) SIG_NAME P5E_CPU1_PE3_RX_DP<14>
J 0
(-140 1035);
DISPLAY 0.659574 (-140 1035);
PAINT MONO (-140 1035);
DISPLAY INVISIBLE (-140 1035);
FORCEPROP 1 LASTPIN (-150 1025) BN 14
J 2
(-138 1033);
DISPLAY 0.680851 (-138 1033);
PAINT GREEN (-138 1033);
FORCEPROP 2 LAST CDS_LIB standard
J 0
(-200 1025);
DISPLAY INVISIBLE (-200 1025);
FORCEPROP 1 LAST BODY_TYPE PLUMBING
J 2
(-200 1075);
DISPLAY 0.872340 (-200 1075);
PAINT GREEN (-200 1075);
DISPLAY INVISIBLE (-200 1075);
FORCEPROP 1 LAST HDL_TAP TRUE
J 2
(-525 900);
DISPLAY 0.872340 (-525 900);
DISPLAY INVISIBLE (-525 900);
FORCEPROP 1 LAST PATH I34
J 2
(-198 1025);
DISPLAY 0.872340 (-198 1025);
PAINT GREEN (-198 1025);
DISPLAY INVISIBLE (-198 1025);
FORCEADD TAP..1
R 2
(-200 1075);
FORCEPROP 3 LASTPIN (-150 1075) SIG_NAME P5E_CPU1_PE3_RX_DP<15>
J 0
(-140 1085);
DISPLAY 0.659574 (-140 1085);
PAINT MONO (-140 1085);
DISPLAY INVISIBLE (-140 1085);
FORCEPROP 1 LASTPIN (-150 1075) BN 15
J 2
(-138 1083);
DISPLAY 0.680851 (-138 1083);
PAINT GREEN (-138 1083);
FORCEPROP 2 LAST CDS_LIB standard
J 0
(-200 1075);
DISPLAY INVISIBLE (-200 1075);
FORCEPROP 1 LAST BODY_TYPE PLUMBING
J 2
(-200 1125);
DISPLAY 0.872340 (-200 1125);
PAINT GREEN (-200 1125);
DISPLAY INVISIBLE (-200 1125);
FORCEPROP 1 LAST HDL_TAP TRUE
J 2
(-525 950);
DISPLAY 0.872340 (-525 950);
DISPLAY INVISIBLE (-525 950);
FORCEPROP 1 LAST PATH I35
J 2
(-198 1075);
DISPLAY 0.872340 (-198 1075);
PAINT GREEN (-198 1075);
DISPLAY INVISIBLE (-198 1075);
FORCEADD TAP..1
R 2
(-200 -375);
FORCEPROP 3 LASTPIN (-150 -375) SIG_NAME P5E_CPU1_PE3_RX_DN<3>
J 0
(-140 -365);
DISPLAY 0.659574 (-140 -365);
PAINT MONO (-140 -365);
DISPLAY INVISIBLE (-140 -365);
FORCEPROP 1 LASTPIN (-150 -375) BN 3
J 2
(-138 -367);
DISPLAY 0.680851 (-138 -367);
PAINT GREEN (-138 -367);
FORCEPROP 2 LAST CDS_LIB standard
J 0
(-200 -375);
DISPLAY INVISIBLE (-200 -375);
FORCEPROP 1 LAST BODY_TYPE PLUMBING
J 2
(-200 -325);
DISPLAY 0.872340 (-200 -325);
PAINT GREEN (-200 -325);
DISPLAY INVISIBLE (-200 -325);
FORCEPROP 1 LAST HDL_TAP TRUE
J 2
(-525 -500);
DISPLAY 0.872340 (-525 -500);
DISPLAY INVISIBLE (-525 -500);
FORCEPROP 1 LAST PATH I4
J 2
(-198 -375);
DISPLAY 0.872340 (-198 -375);
PAINT GREEN (-198 -375);
DISPLAY INVISIBLE (-198 -375);
FORCEADD TAP..1
R 2
(-200 -275);
FORCEPROP 3 LASTPIN (-150 -275) SIG_NAME P5E_CPU1_PE3_RX_DN<5>
J 0
(-140 -265);
DISPLAY 0.659574 (-140 -265);
PAINT MONO (-140 -265);
DISPLAY INVISIBLE (-140 -265);
FORCEPROP 1 LASTPIN (-150 -275) BN 5
J 2
(-138 -267);
DISPLAY 0.680851 (-138 -267);
PAINT GREEN (-138 -267);
FORCEPROP 2 LAST CDS_LIB standard
J 0
(-200 -275);
DISPLAY INVISIBLE (-200 -275);
FORCEPROP 1 LAST BODY_TYPE PLUMBING
J 2
(-200 -225);
DISPLAY 0.872340 (-200 -225);
PAINT GREEN (-200 -225);
DISPLAY INVISIBLE (-200 -225);
FORCEPROP 1 LAST HDL_TAP TRUE
J 2
(-525 -400);
DISPLAY 0.872340 (-525 -400);
DISPLAY INVISIBLE (-525 -400);
FORCEPROP 1 LAST PATH I5
J 2
(-198 -275);
DISPLAY 0.872340 (-198 -275);
PAINT GREEN (-198 -275);
DISPLAY INVISIBLE (-198 -275);
FORCEADD SOCKET4677_AZIF0045P001C01CS..19
(1500 3050);
FORCEPROP 1 LAST PART_NUMBER DGA^7000023
J 0
(450 4100);
DISPLAY 0.723404 (450 4100);
PAINT GREEN (450 4100);
DISPLAY INVISIBLE (450 4100);
FORCEPROP 2 LAST VALUE SOCKET4677_AZIF0045-P001C01CS
J 0
(450 4225);
DISPLAY 1.021277 (450 4225);
FORCEPROP 1 LAST MATERIAL IO
J 0
(450 4025);
DISPLAY 0.723404 (450 4025);
PAINT GREEN (450 4025);
FORCEPROP 2 LAST PART_TYPE SMLF
J 0
(450 4275);
DISPLAY 1.021277 (450 4275);
FORCEPROP 1 LAST $LOCATION U1
J 0
(450 4175);
DISPLAY 0.723404 (450 4175);
PAINT GREEN (450 4175);
FORCEPROP 0 LASTPIN (300 2250) $PN CU9
J 2
(290 2260);
DISPLAY 0.680851 (290 2260);
PAINT MONO (290 2260);
FORCEPROP 0 LASTPIN (300 2300) $PN CY10
J 2
(290 2310);
DISPLAY 0.680851 (290 2310);
PAINT MONO (290 2310);
FORCEPROP 0 LASTPIN (300 2350) $PN DA9
J 2
(290 2360);
DISPLAY 0.680851 (290 2360);
PAINT MONO (290 2360);
FORCEPROP 0 LASTPIN (300 2400) $PN DD10
J 2
(290 2410);
DISPLAY 0.680851 (290 2410);
PAINT MONO (290 2410);
FORCEPROP 0 LASTPIN (300 2450) $PN DE9
J 2
(290 2460);
DISPLAY 0.680851 (290 2460);
PAINT MONO (290 2460);
FORCEPROP 0 LASTPIN (300 2500) $PN DH10
J 2
(290 2510);
DISPLAY 0.680851 (290 2510);
PAINT MONO (290 2510);
FORCEPROP 0 LASTPIN (300 2550) $PN DJ9
J 2
(290 2560);
DISPLAY 0.680851 (290 2560);
PAINT MONO (290 2560);
FORCEPROP 0 LASTPIN (300 2600) $PN DM10
J 2
(290 2610);
DISPLAY 0.680851 (290 2610);
PAINT MONO (290 2610);
FORCEPROP 0 LASTPIN (300 2650) $PN DN9
J 2
(290 2660);
DISPLAY 0.680851 (290 2660);
PAINT MONO (290 2660);
FORCEPROP 0 LASTPIN (300 2700) $PN DT10
J 2
(290 2710);
DISPLAY 0.680851 (290 2710);
PAINT MONO (290 2710);
FORCEPROP 0 LASTPIN (300 2750) $PN DU9
J 2
(290 2760);
DISPLAY 0.680851 (290 2760);
PAINT MONO (290 2760);
FORCEPROP 0 LASTPIN (300 2800) $PN DY10
J 2
(290 2810);
DISPLAY 0.680851 (290 2810);
PAINT MONO (290 2810);
FORCEPROP 0 LASTPIN (300 2850) $PN EA9
J 2
(290 2860);
DISPLAY 0.680851 (290 2860);
PAINT MONO (290 2860);
FORCEPROP 0 LASTPIN (300 2900) $PN ED10
J 2
(290 2910);
DISPLAY 0.680851 (290 2910);
PAINT MONO (290 2910);
FORCEPROP 0 LASTPIN (300 2950) $PN EE9
J 2
(290 2960);
DISPLAY 0.680851 (290 2960);
PAINT MONO (290 2960);
FORCEPROP 0 LASTPIN (300 3000) $PN EH10
J 2
(290 3010);
DISPLAY 0.680851 (290 3010);
PAINT MONO (290 3010);
FORCEPROP 0 LASTPIN (300 3100) $PN CV10
J 2
(290 3110);
DISPLAY 0.680851 (290 3110);
PAINT MONO (290 3110);
FORCEPROP 0 LASTPIN (300 3150) $PN CW11
J 2
(290 3160);
DISPLAY 0.680851 (290 3160);
PAINT MONO (290 3160);
FORCEPROP 0 LASTPIN (300 3200) $PN DB10
J 2
(290 3210);
DISPLAY 0.680851 (290 3210);
PAINT MONO (290 3210);
FORCEPROP 0 LASTPIN (300 3250) $PN DC11
J 2
(290 3260);
DISPLAY 0.680851 (290 3260);
PAINT MONO (290 3260);
FORCEPROP 0 LASTPIN (300 3300) $PN DF10
J 2
(290 3310);
DISPLAY 0.680851 (290 3310);
PAINT MONO (290 3310);
FORCEPROP 0 LASTPIN (300 3350) $PN DG11
J 2
(290 3360);
DISPLAY 0.680851 (290 3360);
PAINT MONO (290 3360);
FORCEPROP 0 LASTPIN (300 3400) $PN DK10
J 2
(290 3410);
DISPLAY 0.680851 (290 3410);
PAINT MONO (290 3410);
FORCEPROP 0 LASTPIN (300 3450) $PN DL11
J 2
(290 3460);
DISPLAY 0.680851 (290 3460);
PAINT MONO (290 3460);
FORCEPROP 0 LASTPIN (300 3500) $PN DP10
J 2
(290 3510);
DISPLAY 0.680851 (290 3510);
PAINT MONO (290 3510);
FORCEPROP 0 LASTPIN (300 3550) $PN DR11
J 2
(290 3560);
DISPLAY 0.680851 (290 3560);
PAINT MONO (290 3560);
FORCEPROP 0 LASTPIN (300 3600) $PN DV10
J 2
(290 3610);
DISPLAY 0.680851 (290 3610);
PAINT MONO (290 3610);
FORCEPROP 0 LASTPIN (300 3650) $PN DW11
J 2
(290 3660);
DISPLAY 0.680851 (290 3660);
PAINT MONO (290 3660);
FORCEPROP 0 LASTPIN (300 3700) $PN EB10
J 2
(290 3710);
DISPLAY 0.680851 (290 3710);
PAINT MONO (290 3710);
FORCEPROP 0 LASTPIN (300 3750) $PN EC11
J 2
(290 3760);
DISPLAY 0.680851 (290 3760);
PAINT MONO (290 3760);
FORCEPROP 0 LASTPIN (300 3800) $PN EF10
J 2
(290 3810);
DISPLAY 0.680851 (290 3810);
PAINT MONO (290 3810);
FORCEPROP 0 LASTPIN (300 3850) $PN EG11
J 2
(290 3860);
DISPLAY 0.680851 (290 3860);
PAINT MONO (290 3860);
FORCEPROP 0 LASTPIN (2700 2250) $PN CU13
J 0
(2710 2260);
DISPLAY 0.680851 (2710 2260);
PAINT MONO (2710 2260);
FORCEPROP 0 LASTPIN (2700 2300) $PN CV14
J 0
(2710 2310);
DISPLAY 0.680851 (2710 2310);
PAINT MONO (2710 2310);
FORCEPROP 0 LASTPIN (2700 2350) $PN DA13
J 0
(2710 2360);
DISPLAY 0.680851 (2710 2360);
PAINT MONO (2710 2360);
FORCEPROP 0 LASTPIN (2700 2400) $PN DB14
J 0
(2710 2410);
DISPLAY 0.680851 (2710 2410);
PAINT MONO (2710 2410);
FORCEPROP 0 LASTPIN (2700 2450) $PN DE13
J 0
(2710 2460);
DISPLAY 0.680851 (2710 2460);
PAINT MONO (2710 2460);
FORCEPROP 0 LASTPIN (2700 2500) $PN DF14
J 0
(2710 2510);
DISPLAY 0.680851 (2710 2510);
PAINT MONO (2710 2510);
FORCEPROP 0 LASTPIN (2700 2550) $PN DJ13
J 0
(2710 2560);
DISPLAY 0.680851 (2710 2560);
PAINT MONO (2710 2560);
FORCEPROP 0 LASTPIN (2700 2600) $PN DK14
J 0
(2710 2610);
DISPLAY 0.680851 (2710 2610);
PAINT MONO (2710 2610);
FORCEPROP 0 LASTPIN (2700 2650) $PN DN13
J 0
(2710 2660);
DISPLAY 0.680851 (2710 2660);
PAINT MONO (2710 2660);
FORCEPROP 0 LASTPIN (2700 2700) $PN DP14
J 0
(2710 2710);
DISPLAY 0.680851 (2710 2710);
PAINT MONO (2710 2710);
FORCEPROP 0 LASTPIN (2700 2750) $PN DU13
J 0
(2710 2760);
DISPLAY 0.680851 (2710 2760);
PAINT MONO (2710 2760);
FORCEPROP 0 LASTPIN (2700 2800) $PN DV14
J 0
(2710 2810);
DISPLAY 0.680851 (2710 2810);
PAINT MONO (2710 2810);
FORCEPROP 0 LASTPIN (2700 2850) $PN EA13
J 0
(2710 2860);
DISPLAY 0.680851 (2710 2860);
PAINT MONO (2710 2860);
FORCEPROP 0 LASTPIN (2700 2900) $PN EB14
J 0
(2710 2910);
DISPLAY 0.680851 (2710 2910);
PAINT MONO (2710 2910);
FORCEPROP 0 LASTPIN (2700 2950) $PN EE13
J 0
(2710 2960);
DISPLAY 0.680851 (2710 2960);
PAINT MONO (2710 2960);
FORCEPROP 0 LASTPIN (2700 3000) $PN EF14
J 0
(2710 3010);
DISPLAY 0.680851 (2710 3010);
PAINT MONO (2710 3010);
FORCEPROP 0 LASTPIN (2700 3100) $PN CT14
J 0
(2710 3110);
DISPLAY 0.680851 (2710 3110);
PAINT MONO (2710 3110);
FORCEPROP 0 LASTPIN (2700 3150) $PN CW15
J 0
(2710 3160);
DISPLAY 0.680851 (2710 3160);
PAINT MONO (2710 3160);
FORCEPROP 0 LASTPIN (2700 3200) $PN CY14
J 0
(2710 3210);
DISPLAY 0.680851 (2710 3210);
PAINT MONO (2710 3210);
FORCEPROP 0 LASTPIN (2700 3250) $PN DC15
J 0
(2710 3260);
DISPLAY 0.680851 (2710 3260);
PAINT MONO (2710 3260);
FORCEPROP 0 LASTPIN (2700 3300) $PN DD14
J 0
(2710 3310);
DISPLAY 0.680851 (2710 3310);
PAINT MONO (2710 3310);
FORCEPROP 0 LASTPIN (2700 3350) $PN DG15
J 0
(2710 3360);
DISPLAY 0.680851 (2710 3360);
PAINT MONO (2710 3360);
FORCEPROP 0 LASTPIN (2700 3400) $PN DH14
J 0
(2710 3410);
DISPLAY 0.680851 (2710 3410);
PAINT MONO (2710 3410);
FORCEPROP 0 LASTPIN (2700 3450) $PN DL15
J 0
(2710 3460);
DISPLAY 0.680851 (2710 3460);
PAINT MONO (2710 3460);
FORCEPROP 0 LASTPIN (2700 3500) $PN DM14
J 0
(2710 3510);
DISPLAY 0.680851 (2710 3510);
PAINT MONO (2710 3510);
FORCEPROP 0 LASTPIN (2700 3550) $PN DR15
J 0
(2710 3560);
DISPLAY 0.680851 (2710 3560);
PAINT MONO (2710 3560);
FORCEPROP 0 LASTPIN (2700 3600) $PN DT14
J 0
(2710 3610);
DISPLAY 0.680851 (2710 3610);
PAINT MONO (2710 3610);
FORCEPROP 0 LASTPIN (2700 3650) $PN DW15
J 0
(2710 3660);
DISPLAY 0.680851 (2710 3660);
PAINT MONO (2710 3660);
FORCEPROP 0 LASTPIN (2700 3700) $PN DY14
J 0
(2710 3710);
DISPLAY 0.680851 (2710 3710);
PAINT MONO (2710 3710);
FORCEPROP 0 LASTPIN (2700 3750) $PN EC15
J 0
(2710 3760);
DISPLAY 0.680851 (2710 3760);
PAINT MONO (2710 3760);
FORCEPROP 0 LASTPIN (2700 3800) $PN ED14
J 0
(2710 3810);
DISPLAY 0.680851 (2710 3810);
PAINT MONO (2710 3810);
FORCEPROP 0 LASTPIN (2700 3850) $PN EG15
J 0
(2710 3860);
DISPLAY 0.680851 (2710 3860);
PAINT MONO (2710 3860);
FORCEPROP 1 LAST CDS_LMAN_SYM_OUTLINE -1050,950,1050,-950
J 0
(1500 3050);
DISPLAY 0.468085 (1500 3050);
PAINT GREEN (1500 3050);
DISPLAY INVISIBLE (1500 3050);
FORCEPROP 1 LAST NEEDS_NO_SIZE TRUE
J 0
(1500 3050);
DISPLAY 0.723404 (1500 3050);
PAINT GREEN (1500 3050);
DISPLAY INVISIBLE (1500 3050);
FORCEPROP 2 LAST CDS_LIB pure_quanta
J 0
(1500 3050);
DISPLAY INVISIBLE (1500 3050);
FORCEPROP 2 LAST CDS_LOCATION U1
J 0
(450 4325);
DISPLAY 1.021277 (450 4325);
DISPLAY INVISIBLE (450 4325);
FORCEPROP 0 LAST $SEC 19
J 0
(450 4325);
DISPLAY 0.680851 (450 4325);
PAINT MONO (450 4325);
DISPLAY INVISIBLE (450 4325);
FORCEPROP 2 LAST CDS_SEC 19
J 0
(450 4325);
DISPLAY 1.021277 (450 4325);
DISPLAY INVISIBLE (450 4325);
FORCEPROP 1 LAST PATH I54
J 0
(1500 3050);
DISPLAY 0.723404 (1500 3050);
PAINT GREEN (1500 3050);
DISPLAY INVISIBLE (1500 3050);
FORCEADD TAP..1
R 2
(-200 -325);
FORCEPROP 3 LASTPIN (-150 -325) SIG_NAME P5E_CPU1_PE3_RX_DN<4>
J 0
(-140 -315);
DISPLAY 0.659574 (-140 -315);
PAINT MONO (-140 -315);
DISPLAY INVISIBLE (-140 -315);
FORCEPROP 1 LASTPIN (-150 -325) BN 4
J 2
(-138 -317);
DISPLAY 0.680851 (-138 -317);
PAINT GREEN (-138 -317);
FORCEPROP 2 LAST CDS_LIB standard
J 0
(-200 -325);
DISPLAY INVISIBLE (-200 -325);
FORCEPROP 1 LAST BODY_TYPE PLUMBING
J 2
(-200 -275);
DISPLAY 0.872340 (-200 -275);
PAINT GREEN (-200 -275);
DISPLAY INVISIBLE (-200 -275);
FORCEPROP 1 LAST HDL_TAP TRUE
J 2
(-525 -450);
DISPLAY 0.872340 (-525 -450);
DISPLAY INVISIBLE (-525 -450);
FORCEPROP 1 LAST PATH I6
J 2
(-198 -325);
DISPLAY 0.872340 (-198 -325);
PAINT GREEN (-198 -325);
DISPLAY INVISIBLE (-198 -325);
FORCEADD TAP..1
R 2
(-200 -225);
FORCEPROP 3 LASTPIN (-150 -225) SIG_NAME P5E_CPU1_PE3_RX_DN<6>
J 0
(-140 -215);
DISPLAY 0.659574 (-140 -215);
PAINT MONO (-140 -215);
DISPLAY INVISIBLE (-140 -215);
FORCEPROP 1 LASTPIN (-150 -225) BN 6
J 2
(-138 -217);
DISPLAY 0.680851 (-138 -217);
PAINT GREEN (-138 -217);
FORCEPROP 2 LAST CDS_LIB standard
J 0
(-200 -225);
DISPLAY INVISIBLE (-200 -225);
FORCEPROP 1 LAST BODY_TYPE PLUMBING
J 2
(-200 -175);
DISPLAY 0.872340 (-200 -175);
PAINT GREEN (-200 -175);
DISPLAY INVISIBLE (-200 -175);
FORCEPROP 1 LAST HDL_TAP TRUE
J 2
(-525 -350);
DISPLAY 0.872340 (-525 -350);
DISPLAY INVISIBLE (-525 -350);
FORCEPROP 1 LAST PATH I7
J 2
(-198 -225);
DISPLAY 0.872340 (-198 -225);
PAINT GREEN (-198 -225);
DISPLAY INVISIBLE (-198 -225);
FORCEADD TAP..1
(3175 -525);
FORCEPROP 3 LASTPIN (3125 -525) SIG_NAME P5E_CPU1_PE3_TX_DN<0>
J 0
(3135 -515);
DISPLAY 0.659574 (3135 -515);
PAINT MONO (3135 -515);
DISPLAY INVISIBLE (3135 -515);
FORCEPROP 1 LASTPIN (3125 -525) BN 0
J 0
(3113 -517);
DISPLAY 0.680851 (3113 -517);
PAINT GREEN (3113 -517);
FORCEPROP 2 LAST CDS_LIB standard
J 0
(3175 -525);
PAINT MONO (3175 -525);
DISPLAY INVISIBLE (3175 -525);
FORCEPROP 1 LAST BODY_TYPE PLUMBING
J 0
(3175 -475);
DISPLAY 0.872340 (3175 -475);
PAINT GREEN (3175 -475);
DISPLAY INVISIBLE (3175 -475);
FORCEPROP 1 LAST HDL_TAP TRUE
J 0
(3500 -650);
DISPLAY 0.872340 (3500 -650);
DISPLAY INVISIBLE (3500 -650);
FORCEPROP 1 LAST PATH I71
J 0
(3173 -525);
DISPLAY 0.872340 (3173 -525);
PAINT GREEN (3173 -525);
DISPLAY INVISIBLE (3173 -525);
FORCEADD TAP..1
(3175 -475);
FORCEPROP 3 LASTPIN (3125 -475) SIG_NAME P5E_CPU1_PE3_TX_DN<1>
J 0
(3135 -465);
DISPLAY 0.659574 (3135 -465);
PAINT MONO (3135 -465);
DISPLAY INVISIBLE (3135 -465);
FORCEPROP 1 LASTPIN (3125 -475) BN 1
J 0
(3113 -467);
DISPLAY 0.680851 (3113 -467);
PAINT GREEN (3113 -467);
FORCEPROP 2 LAST CDS_LIB standard
J 0
(3175 -475);
PAINT MONO (3175 -475);
DISPLAY INVISIBLE (3175 -475);
FORCEPROP 1 LAST BODY_TYPE PLUMBING
J 0
(3175 -425);
DISPLAY 0.872340 (3175 -425);
PAINT GREEN (3175 -425);
DISPLAY INVISIBLE (3175 -425);
FORCEPROP 1 LAST HDL_TAP TRUE
J 0
(3500 -600);
DISPLAY 0.872340 (3500 -600);
DISPLAY INVISIBLE (3500 -600);
FORCEPROP 1 LAST PATH I72
J 0
(3173 -475);
DISPLAY 0.872340 (3173 -475);
PAINT GREEN (3173 -475);
DISPLAY INVISIBLE (3173 -475);
FORCEADD TAP..1
(3175 -425);
FORCEPROP 3 LASTPIN (3125 -425) SIG_NAME P5E_CPU1_PE3_TX_DN<2>
J 0
(3135 -415);
DISPLAY 0.659574 (3135 -415);
PAINT MONO (3135 -415);
DISPLAY INVISIBLE (3135 -415);
FORCEPROP 1 LASTPIN (3125 -425) BN 2
J 0
(3113 -417);
DISPLAY 0.680851 (3113 -417);
PAINT GREEN (3113 -417);
FORCEPROP 2 LAST CDS_LIB standard
J 0
(3175 -425);
PAINT MONO (3175 -425);
DISPLAY INVISIBLE (3175 -425);
FORCEPROP 1 LAST BODY_TYPE PLUMBING
J 0
(3175 -375);
DISPLAY 0.872340 (3175 -375);
PAINT GREEN (3175 -375);
DISPLAY INVISIBLE (3175 -375);
FORCEPROP 1 LAST HDL_TAP TRUE
J 0
(3500 -550);
DISPLAY 0.872340 (3500 -550);
DISPLAY INVISIBLE (3500 -550);
FORCEPROP 1 LAST PATH I73
J 0
(3173 -425);
DISPLAY 0.872340 (3173 -425);
PAINT GREEN (3173 -425);
DISPLAY INVISIBLE (3173 -425);
FORCEADD TAP..1
(3175 -375);
FORCEPROP 3 LASTPIN (3125 -375) SIG_NAME P5E_CPU1_PE3_TX_DN<3>
J 0
(3135 -365);
DISPLAY 0.659574 (3135 -365);
PAINT MONO (3135 -365);
DISPLAY INVISIBLE (3135 -365);
FORCEPROP 1 LASTPIN (3125 -375) BN 3
J 0
(3113 -367);
DISPLAY 0.680851 (3113 -367);
PAINT GREEN (3113 -367);
FORCEPROP 2 LAST CDS_LIB standard
J 0
(3175 -375);
PAINT MONO (3175 -375);
DISPLAY INVISIBLE (3175 -375);
FORCEPROP 1 LAST BODY_TYPE PLUMBING
J 0
(3175 -325);
DISPLAY 0.872340 (3175 -325);
PAINT GREEN (3175 -325);
DISPLAY INVISIBLE (3175 -325);
FORCEPROP 1 LAST HDL_TAP TRUE
J 0
(3500 -500);
DISPLAY 0.872340 (3500 -500);
DISPLAY INVISIBLE (3500 -500);
FORCEPROP 1 LAST PATH I74
J 0
(3173 -375);
DISPLAY 0.872340 (3173 -375);
PAINT GREEN (3173 -375);
DISPLAY INVISIBLE (3173 -375);
FORCEADD TAP..1
(3175 -325);
FORCEPROP 3 LASTPIN (3125 -325) SIG_NAME P5E_CPU1_PE3_TX_DN<4>
J 0
(3135 -315);
DISPLAY 0.659574 (3135 -315);
PAINT MONO (3135 -315);
DISPLAY INVISIBLE (3135 -315);
FORCEPROP 1 LASTPIN (3125 -325) BN 4
J 0
(3113 -317);
DISPLAY 0.680851 (3113 -317);
PAINT GREEN (3113 -317);
FORCEPROP 2 LAST CDS_LIB standard
J 0
(3175 -325);
PAINT MONO (3175 -325);
DISPLAY INVISIBLE (3175 -325);
FORCEPROP 1 LAST BODY_TYPE PLUMBING
J 0
(3175 -275);
DISPLAY 0.872340 (3175 -275);
PAINT GREEN (3175 -275);
DISPLAY INVISIBLE (3175 -275);
FORCEPROP 1 LAST HDL_TAP TRUE
J 0
(3500 -450);
DISPLAY 0.872340 (3500 -450);
DISPLAY INVISIBLE (3500 -450);
FORCEPROP 1 LAST PATH I75
J 0
(3173 -325);
DISPLAY 0.872340 (3173 -325);
PAINT GREEN (3173 -325);
DISPLAY INVISIBLE (3173 -325);
FORCEADD TAP..1
(3175 -275);
FORCEPROP 3 LASTPIN (3125 -275) SIG_NAME P5E_CPU1_PE3_TX_DN<5>
J 0
(3135 -265);
DISPLAY 0.659574 (3135 -265);
PAINT MONO (3135 -265);
DISPLAY INVISIBLE (3135 -265);
FORCEPROP 1 LASTPIN (3125 -275) BN 5
J 0
(3113 -267);
DISPLAY 0.680851 (3113 -267);
PAINT GREEN (3113 -267);
FORCEPROP 2 LAST CDS_LIB standard
J 0
(3175 -275);
PAINT MONO (3175 -275);
DISPLAY INVISIBLE (3175 -275);
FORCEPROP 1 LAST BODY_TYPE PLUMBING
J 0
(3175 -225);
DISPLAY 0.872340 (3175 -225);
PAINT GREEN (3175 -225);
DISPLAY INVISIBLE (3175 -225);
FORCEPROP 1 LAST HDL_TAP TRUE
J 0
(3500 -400);
DISPLAY 0.872340 (3500 -400);
DISPLAY INVISIBLE (3500 -400);
FORCEPROP 1 LAST PATH I76
J 0
(3173 -275);
DISPLAY 0.872340 (3173 -275);
PAINT GREEN (3173 -275);
DISPLAY INVISIBLE (3173 -275);
FORCEADD TAP..1
(3175 -225);
FORCEPROP 3 LASTPIN (3125 -225) SIG_NAME P5E_CPU1_PE3_TX_DN<6>
J 0
(3135 -215);
DISPLAY 0.659574 (3135 -215);
PAINT MONO (3135 -215);
DISPLAY INVISIBLE (3135 -215);
FORCEPROP 1 LASTPIN (3125 -225) BN 6
J 0
(3113 -217);
DISPLAY 0.680851 (3113 -217);
PAINT GREEN (3113 -217);
FORCEPROP 2 LAST CDS_LIB standard
J 0
(3175 -225);
PAINT MONO (3175 -225);
DISPLAY INVISIBLE (3175 -225);
FORCEPROP 1 LAST BODY_TYPE PLUMBING
J 0
(3175 -175);
DISPLAY 0.872340 (3175 -175);
PAINT GREEN (3175 -175);
DISPLAY INVISIBLE (3175 -175);
FORCEPROP 1 LAST HDL_TAP TRUE
J 0
(3500 -350);
DISPLAY 0.872340 (3500 -350);
DISPLAY INVISIBLE (3500 -350);
FORCEPROP 1 LAST PATH I77
J 0
(3173 -225);
DISPLAY 0.872340 (3173 -225);
PAINT GREEN (3173 -225);
DISPLAY INVISIBLE (3173 -225);
FORCEADD TAP..1
(3175 -175);
FORCEPROP 3 LASTPIN (3125 -175) SIG_NAME P5E_CPU1_PE3_TX_DN<7>
J 0
(3135 -165);
DISPLAY 0.659574 (3135 -165);
PAINT MONO (3135 -165);
DISPLAY INVISIBLE (3135 -165);
FORCEPROP 1 LASTPIN (3125 -175) BN 7
J 0
(3113 -167);
DISPLAY 0.680851 (3113 -167);
PAINT GREEN (3113 -167);
FORCEPROP 2 LAST CDS_LIB standard
J 0
(3175 -175);
PAINT MONO (3175 -175);
DISPLAY INVISIBLE (3175 -175);
FORCEPROP 1 LAST BODY_TYPE PLUMBING
J 0
(3175 -125);
DISPLAY 0.872340 (3175 -125);
PAINT GREEN (3175 -125);
DISPLAY INVISIBLE (3175 -125);
FORCEPROP 1 LAST HDL_TAP TRUE
J 0
(3500 -300);
DISPLAY 0.872340 (3500 -300);
DISPLAY INVISIBLE (3500 -300);
FORCEPROP 1 LAST PATH I78
J 0
(3173 -175);
DISPLAY 0.872340 (3173 -175);
PAINT GREEN (3173 -175);
DISPLAY INVISIBLE (3173 -175);
FORCEADD TAP..1
(3175 -125);
FORCEPROP 3 LASTPIN (3125 -125) SIG_NAME P5E_CPU1_PE3_TX_DN<8>
J 0
(3135 -115);
DISPLAY 0.659574 (3135 -115);
PAINT MONO (3135 -115);
DISPLAY INVISIBLE (3135 -115);
FORCEPROP 1 LASTPIN (3125 -125) BN 8
J 0
(3113 -117);
DISPLAY 0.680851 (3113 -117);
PAINT GREEN (3113 -117);
FORCEPROP 2 LAST CDS_LIB standard
J 0
(3175 -125);
PAINT MONO (3175 -125);
DISPLAY INVISIBLE (3175 -125);
FORCEPROP 1 LAST BODY_TYPE PLUMBING
J 0
(3175 -75);
DISPLAY 0.872340 (3175 -75);
PAINT GREEN (3175 -75);
DISPLAY INVISIBLE (3175 -75);
FORCEPROP 1 LAST HDL_TAP TRUE
J 0
(3500 -250);
DISPLAY 0.872340 (3500 -250);
DISPLAY INVISIBLE (3500 -250);
FORCEPROP 1 LAST PATH I79
J 0
(3173 -125);
DISPLAY 0.872340 (3173 -125);
PAINT GREEN (3173 -125);
DISPLAY INVISIBLE (3173 -125);
FORCEADD TAP..1
R 2
(-200 -175);
FORCEPROP 3 LASTPIN (-150 -175) SIG_NAME P5E_CPU1_PE3_RX_DN<7>
J 0
(-140 -165);
DISPLAY 0.659574 (-140 -165);
PAINT MONO (-140 -165);
DISPLAY INVISIBLE (-140 -165);
FORCEPROP 1 LASTPIN (-150 -175) BN 7
J 2
(-138 -167);
DISPLAY 0.680851 (-138 -167);
PAINT GREEN (-138 -167);
FORCEPROP 2 LAST CDS_LIB standard
J 0
(-200 -175);
DISPLAY INVISIBLE (-200 -175);
FORCEPROP 1 LAST BODY_TYPE PLUMBING
J 2
(-200 -125);
DISPLAY 0.872340 (-200 -125);
PAINT GREEN (-200 -125);
DISPLAY INVISIBLE (-200 -125);
FORCEPROP 1 LAST HDL_TAP TRUE
J 2
(-525 -300);
DISPLAY 0.872340 (-525 -300);
DISPLAY INVISIBLE (-525 -300);
FORCEPROP 1 LAST PATH I8
J 2
(-198 -175);
DISPLAY 0.872340 (-198 -175);
PAINT GREEN (-198 -175);
DISPLAY INVISIBLE (-198 -175);
FORCEADD TAP..1
(3175 -25);
FORCEPROP 3 LASTPIN (3125 -25) SIG_NAME P5E_CPU1_PE3_TX_DN<10>
J 0
(3135 -15);
DISPLAY 0.659574 (3135 -15);
PAINT MONO (3135 -15);
DISPLAY INVISIBLE (3135 -15);
FORCEPROP 1 LASTPIN (3125 -25) BN 10
J 0
(3113 -17);
DISPLAY 0.680851 (3113 -17);
PAINT GREEN (3113 -17);
FORCEPROP 2 LAST CDS_LIB standard
J 0
(3175 -25);
DISPLAY INVISIBLE (3175 -25);
FORCEPROP 1 LAST BODY_TYPE PLUMBING
J 0
(3175 25);
DISPLAY 0.872340 (3175 25);
PAINT GREEN (3175 25);
DISPLAY INVISIBLE (3175 25);
FORCEPROP 1 LAST HDL_TAP TRUE
J 0
(3500 -150);
DISPLAY 0.872340 (3500 -150);
DISPLAY INVISIBLE (3500 -150);
FORCEPROP 1 LAST PATH I80
J 0
(3173 -25);
DISPLAY 0.872340 (3173 -25);
PAINT GREEN (3173 -25);
DISPLAY INVISIBLE (3173 -25);
FORCEADD TAP..1
(3175 -75);
FORCEPROP 3 LASTPIN (3125 -75) SIG_NAME P5E_CPU1_PE3_TX_DN<9>
J 0
(3135 -65);
DISPLAY 0.659574 (3135 -65);
PAINT MONO (3135 -65);
DISPLAY INVISIBLE (3135 -65);
FORCEPROP 1 LASTPIN (3125 -75) BN 9
J 0
(3113 -67);
DISPLAY 0.680851 (3113 -67);
PAINT GREEN (3113 -67);
FORCEPROP 2 LAST CDS_LIB standard
J 0
(3175 -75);
DISPLAY INVISIBLE (3175 -75);
FORCEPROP 1 LAST BODY_TYPE PLUMBING
J 0
(3175 -25);
DISPLAY 0.872340 (3175 -25);
PAINT GREEN (3175 -25);
DISPLAY INVISIBLE (3175 -25);
FORCEPROP 1 LAST HDL_TAP TRUE
J 0
(3500 -200);
DISPLAY 0.872340 (3500 -200);
DISPLAY INVISIBLE (3500 -200);
FORCEPROP 1 LAST PATH I81
J 0
(3173 -75);
DISPLAY 0.872340 (3173 -75);
PAINT GREEN (3173 -75);
DISPLAY INVISIBLE (3173 -75);
FORCEADD TAP..1
(3175 25);
FORCEPROP 3 LASTPIN (3125 25) SIG_NAME P5E_CPU1_PE3_TX_DN<11>
J 0
(3135 35);
DISPLAY 0.659574 (3135 35);
PAINT MONO (3135 35);
DISPLAY INVISIBLE (3135 35);
FORCEPROP 1 LASTPIN (3125 25) BN 11
J 0
(3113 33);
DISPLAY 0.680851 (3113 33);
PAINT GREEN (3113 33);
FORCEPROP 2 LAST CDS_LIB standard
J 0
(3175 25);
DISPLAY INVISIBLE (3175 25);
FORCEPROP 1 LAST BODY_TYPE PLUMBING
J 0
(3175 75);
DISPLAY 0.872340 (3175 75);
PAINT GREEN (3175 75);
DISPLAY INVISIBLE (3175 75);
FORCEPROP 1 LAST HDL_TAP TRUE
J 0
(3500 -100);
DISPLAY 0.872340 (3500 -100);
DISPLAY INVISIBLE (3500 -100);
FORCEPROP 1 LAST PATH I82
J 0
(3173 25);
DISPLAY 0.872340 (3173 25);
PAINT GREEN (3173 25);
DISPLAY INVISIBLE (3173 25);
FORCEADD TAP..1
(3175 75);
FORCEPROP 3 LASTPIN (3125 75) SIG_NAME P5E_CPU1_PE3_TX_DN<12>
J 0
(3135 85);
DISPLAY 0.659574 (3135 85);
PAINT MONO (3135 85);
DISPLAY INVISIBLE (3135 85);
FORCEPROP 1 LASTPIN (3125 75) BN 12
J 0
(3113 83);
DISPLAY 0.680851 (3113 83);
PAINT GREEN (3113 83);
FORCEPROP 2 LAST CDS_LIB standard
J 0
(3175 75);
DISPLAY INVISIBLE (3175 75);
FORCEPROP 1 LAST BODY_TYPE PLUMBING
J 0
(3175 125);
DISPLAY 0.872340 (3175 125);
PAINT GREEN (3175 125);
DISPLAY INVISIBLE (3175 125);
FORCEPROP 1 LAST HDL_TAP TRUE
J 0
(3500 -50);
DISPLAY 0.872340 (3500 -50);
DISPLAY INVISIBLE (3500 -50);
FORCEPROP 1 LAST PATH I83
J 0
(3173 75);
DISPLAY 0.872340 (3173 75);
PAINT GREEN (3173 75);
DISPLAY INVISIBLE (3173 75);
FORCEADD TAP..1
(3175 125);
FORCEPROP 3 LASTPIN (3125 125) SIG_NAME P5E_CPU1_PE3_TX_DN<13>
J 0
(3135 135);
DISPLAY 0.659574 (3135 135);
PAINT MONO (3135 135);
DISPLAY INVISIBLE (3135 135);
FORCEPROP 1 LASTPIN (3125 125) BN 13
J 0
(3113 133);
DISPLAY 0.680851 (3113 133);
PAINT GREEN (3113 133);
FORCEPROP 2 LAST CDS_LIB standard
J 0
(3175 125);
DISPLAY INVISIBLE (3175 125);
FORCEPROP 1 LAST BODY_TYPE PLUMBING
J 0
(3175 175);
DISPLAY 0.872340 (3175 175);
PAINT GREEN (3175 175);
DISPLAY INVISIBLE (3175 175);
FORCEPROP 1 LAST HDL_TAP TRUE
J 0
(3500 0);
DISPLAY 0.872340 (3500 0);
DISPLAY INVISIBLE (3500 0);
FORCEPROP 1 LAST PATH I84
J 0
(3173 125);
DISPLAY 0.872340 (3173 125);
PAINT GREEN (3173 125);
DISPLAY INVISIBLE (3173 125);
FORCEADD TAP..1
(3175 175);
FORCEPROP 3 LASTPIN (3125 175) SIG_NAME P5E_CPU1_PE3_TX_DN<14>
J 0
(3135 185);
DISPLAY 0.659574 (3135 185);
PAINT MONO (3135 185);
DISPLAY INVISIBLE (3135 185);
FORCEPROP 1 LASTPIN (3125 175) BN 14
J 0
(3113 183);
DISPLAY 0.680851 (3113 183);
PAINT GREEN (3113 183);
FORCEPROP 2 LAST CDS_LIB standard
J 0
(3175 175);
DISPLAY INVISIBLE (3175 175);
FORCEPROP 1 LAST BODY_TYPE PLUMBING
J 0
(3175 225);
DISPLAY 0.872340 (3175 225);
PAINT GREEN (3175 225);
DISPLAY INVISIBLE (3175 225);
FORCEPROP 1 LAST HDL_TAP TRUE
J 0
(3500 50);
DISPLAY 0.872340 (3500 50);
DISPLAY INVISIBLE (3500 50);
FORCEPROP 1 LAST PATH I85
J 0
(3173 175);
DISPLAY 0.872340 (3173 175);
PAINT GREEN (3173 175);
DISPLAY INVISIBLE (3173 175);
FORCEADD TAP..1
(3175 225);
FORCEPROP 3 LASTPIN (3125 225) SIG_NAME P5E_CPU1_PE3_TX_DN<15>
J 0
(3135 235);
DISPLAY 0.659574 (3135 235);
PAINT MONO (3135 235);
DISPLAY INVISIBLE (3135 235);
FORCEPROP 1 LASTPIN (3125 225) BN 15
J 0
(3113 233);
DISPLAY 0.680851 (3113 233);
PAINT GREEN (3113 233);
FORCEPROP 2 LAST CDS_LIB standard
J 0
(3175 225);
DISPLAY INVISIBLE (3175 225);
FORCEPROP 1 LAST BODY_TYPE PLUMBING
J 0
(3175 275);
DISPLAY 0.872340 (3175 275);
PAINT GREEN (3175 275);
DISPLAY INVISIBLE (3175 275);
FORCEPROP 1 LAST HDL_TAP TRUE
J 0
(3500 100);
DISPLAY 0.872340 (3500 100);
DISPLAY INVISIBLE (3500 100);
FORCEPROP 1 LAST PATH I86
J 0
(3173 225);
DISPLAY 0.872340 (3173 225);
PAINT GREEN (3173 225);
DISPLAY INVISIBLE (3173 225);
FORCEADD TAP..1
(3175 325);
FORCEPROP 3 LASTPIN (3125 325) SIG_NAME P5E_CPU1_PE3_TX_DP<0>
J 0
(3135 335);
DISPLAY 0.659574 (3135 335);
PAINT MONO (3135 335);
DISPLAY INVISIBLE (3135 335);
FORCEPROP 1 LASTPIN (3125 325) BN 0
J 0
(3113 333);
DISPLAY 0.680851 (3113 333);
PAINT GREEN (3113 333);
FORCEPROP 2 LAST CDS_LIB standard
J 0
(3175 325);
PAINT MONO (3175 325);
DISPLAY INVISIBLE (3175 325);
FORCEPROP 1 LAST BODY_TYPE PLUMBING
J 0
(3175 375);
DISPLAY 0.872340 (3175 375);
PAINT GREEN (3175 375);
DISPLAY INVISIBLE (3175 375);
FORCEPROP 1 LAST HDL_TAP TRUE
J 0
(3500 200);
DISPLAY 0.872340 (3500 200);
DISPLAY INVISIBLE (3500 200);
FORCEPROP 1 LAST PATH I87
J 0
(3173 325);
DISPLAY 0.872340 (3173 325);
PAINT GREEN (3173 325);
DISPLAY INVISIBLE (3173 325);
FORCEADD TAP..1
(3175 375);
FORCEPROP 3 LASTPIN (3125 375) SIG_NAME P5E_CPU1_PE3_TX_DP<1>
J 0
(3135 385);
DISPLAY 0.659574 (3135 385);
PAINT MONO (3135 385);
DISPLAY INVISIBLE (3135 385);
FORCEPROP 1 LASTPIN (3125 375) BN 1
J 0
(3113 383);
DISPLAY 0.680851 (3113 383);
PAINT GREEN (3113 383);
FORCEPROP 2 LAST CDS_LIB standard
J 0
(3175 375);
PAINT MONO (3175 375);
DISPLAY INVISIBLE (3175 375);
FORCEPROP 1 LAST BODY_TYPE PLUMBING
J 0
(3175 425);
DISPLAY 0.872340 (3175 425);
PAINT GREEN (3175 425);
DISPLAY INVISIBLE (3175 425);
FORCEPROP 1 LAST HDL_TAP TRUE
J 0
(3500 250);
DISPLAY 0.872340 (3500 250);
DISPLAY INVISIBLE (3500 250);
FORCEPROP 1 LAST PATH I88
J 0
(3173 375);
DISPLAY 0.872340 (3173 375);
PAINT GREEN (3173 375);
DISPLAY INVISIBLE (3173 375);
FORCEADD TAP..1
(3175 475);
FORCEPROP 3 LASTPIN (3125 475) SIG_NAME P5E_CPU1_PE3_TX_DP<3>
J 0
(3135 485);
DISPLAY 0.659574 (3135 485);
PAINT MONO (3135 485);
DISPLAY INVISIBLE (3135 485);
FORCEPROP 1 LASTPIN (3125 475) BN 3
J 0
(3113 483);
DISPLAY 0.680851 (3113 483);
PAINT GREEN (3113 483);
FORCEPROP 2 LAST CDS_LIB standard
J 0
(3175 475);
PAINT MONO (3175 475);
DISPLAY INVISIBLE (3175 475);
FORCEPROP 1 LAST BODY_TYPE PLUMBING
J 0
(3175 525);
DISPLAY 0.872340 (3175 525);
PAINT GREEN (3175 525);
DISPLAY INVISIBLE (3175 525);
FORCEPROP 1 LAST HDL_TAP TRUE
J 0
(3500 350);
DISPLAY 0.872340 (3500 350);
DISPLAY INVISIBLE (3500 350);
FORCEPROP 1 LAST PATH I89
J 0
(3173 475);
DISPLAY 0.872340 (3173 475);
PAINT GREEN (3173 475);
DISPLAY INVISIBLE (3173 475);
FORCEADD TAP..1
R 2
(-200 -75);
FORCEPROP 3 LASTPIN (-150 -75) SIG_NAME P5E_CPU1_PE3_RX_DN<9>
J 0
(-140 -65);
DISPLAY 0.659574 (-140 -65);
PAINT MONO (-140 -65);
DISPLAY INVISIBLE (-140 -65);
FORCEPROP 1 LASTPIN (-150 -75) BN 9
J 2
(-138 -67);
DISPLAY 0.680851 (-138 -67);
PAINT GREEN (-138 -67);
FORCEPROP 2 LAST CDS_LIB standard
J 0
(-200 -75);
DISPLAY INVISIBLE (-200 -75);
FORCEPROP 1 LAST BODY_TYPE PLUMBING
J 2
(-200 -25);
DISPLAY 0.872340 (-200 -25);
PAINT GREEN (-200 -25);
DISPLAY INVISIBLE (-200 -25);
FORCEPROP 1 LAST HDL_TAP TRUE
J 2
(-525 -200);
DISPLAY 0.872340 (-525 -200);
DISPLAY INVISIBLE (-525 -200);
FORCEPROP 1 LAST PATH I9
J 2
(-198 -75);
DISPLAY 0.872340 (-198 -75);
PAINT GREEN (-198 -75);
DISPLAY INVISIBLE (-198 -75);
FORCEADD TAP..1
(3175 525);
FORCEPROP 3 LASTPIN (3125 525) SIG_NAME P5E_CPU1_PE3_TX_DP<4>
J 0
(3135 535);
DISPLAY 0.659574 (3135 535);
PAINT MONO (3135 535);
DISPLAY INVISIBLE (3135 535);
FORCEPROP 1 LASTPIN (3125 525) BN 4
J 0
(3113 533);
DISPLAY 0.680851 (3113 533);
PAINT GREEN (3113 533);
FORCEPROP 2 LAST CDS_LIB standard
J 0
(3175 525);
PAINT MONO (3175 525);
DISPLAY INVISIBLE (3175 525);
FORCEPROP 1 LAST BODY_TYPE PLUMBING
J 0
(3175 575);
DISPLAY 0.872340 (3175 575);
PAINT GREEN (3175 575);
DISPLAY INVISIBLE (3175 575);
FORCEPROP 1 LAST HDL_TAP TRUE
J 0
(3500 400);
DISPLAY 0.872340 (3500 400);
DISPLAY INVISIBLE (3500 400);
FORCEPROP 1 LAST PATH I90
J 0
(3173 525);
DISPLAY 0.872340 (3173 525);
PAINT GREEN (3173 525);
DISPLAY INVISIBLE (3173 525);
FORCEADD TAP..1
(3175 425);
FORCEPROP 3 LASTPIN (3125 425) SIG_NAME P5E_CPU1_PE3_TX_DP<2>
J 0
(3135 435);
DISPLAY 0.659574 (3135 435);
PAINT MONO (3135 435);
DISPLAY INVISIBLE (3135 435);
FORCEPROP 1 LASTPIN (3125 425) BN 2
J 0
(3113 433);
DISPLAY 0.680851 (3113 433);
PAINT GREEN (3113 433);
FORCEPROP 2 LAST CDS_LIB standard
J 0
(3175 425);
PAINT MONO (3175 425);
DISPLAY INVISIBLE (3175 425);
FORCEPROP 1 LAST BODY_TYPE PLUMBING
J 0
(3175 475);
DISPLAY 0.872340 (3175 475);
PAINT GREEN (3175 475);
DISPLAY INVISIBLE (3175 475);
FORCEPROP 1 LAST HDL_TAP TRUE
J 0
(3500 300);
DISPLAY 0.872340 (3500 300);
DISPLAY INVISIBLE (3500 300);
FORCEPROP 1 LAST PATH I91
J 0
(3173 425);
DISPLAY 0.872340 (3173 425);
PAINT GREEN (3173 425);
DISPLAY INVISIBLE (3173 425);
FORCEADD TAP..1
(3175 575);
FORCEPROP 3 LASTPIN (3125 575) SIG_NAME P5E_CPU1_PE3_TX_DP<5>
J 0
(3135 585);
DISPLAY 0.659574 (3135 585);
PAINT MONO (3135 585);
DISPLAY INVISIBLE (3135 585);
FORCEPROP 1 LASTPIN (3125 575) BN 5
J 0
(3113 583);
DISPLAY 0.680851 (3113 583);
PAINT GREEN (3113 583);
FORCEPROP 2 LAST CDS_LIB standard
J 0
(3175 575);
PAINT MONO (3175 575);
DISPLAY INVISIBLE (3175 575);
FORCEPROP 1 LAST BODY_TYPE PLUMBING
J 0
(3175 625);
DISPLAY 0.872340 (3175 625);
PAINT GREEN (3175 625);
DISPLAY INVISIBLE (3175 625);
FORCEPROP 1 LAST HDL_TAP TRUE
J 0
(3500 450);
DISPLAY 0.872340 (3500 450);
DISPLAY INVISIBLE (3500 450);
FORCEPROP 1 LAST PATH I92
J 0
(3173 575);
DISPLAY 0.872340 (3173 575);
PAINT GREEN (3173 575);
DISPLAY INVISIBLE (3173 575);
FORCEADD TAP..1
(3175 625);
FORCEPROP 3 LASTPIN (3125 625) SIG_NAME P5E_CPU1_PE3_TX_DP<6>
J 0
(3135 635);
DISPLAY 0.659574 (3135 635);
PAINT MONO (3135 635);
DISPLAY INVISIBLE (3135 635);
FORCEPROP 1 LASTPIN (3125 625) BN 6
J 0
(3113 633);
DISPLAY 0.680851 (3113 633);
PAINT GREEN (3113 633);
FORCEPROP 2 LAST CDS_LIB standard
J 0
(3175 625);
PAINT MONO (3175 625);
DISPLAY INVISIBLE (3175 625);
FORCEPROP 1 LAST BODY_TYPE PLUMBING
J 0
(3175 675);
DISPLAY 0.872340 (3175 675);
PAINT GREEN (3175 675);
DISPLAY INVISIBLE (3175 675);
FORCEPROP 1 LAST HDL_TAP TRUE
J 0
(3500 500);
DISPLAY 0.872340 (3500 500);
DISPLAY INVISIBLE (3500 500);
FORCEPROP 1 LAST PATH I93
J 0
(3173 625);
DISPLAY 0.872340 (3173 625);
PAINT GREEN (3173 625);
DISPLAY INVISIBLE (3173 625);
FORCEADD TAP..1
(3175 675);
FORCEPROP 3 LASTPIN (3125 675) SIG_NAME P5E_CPU1_PE3_TX_DP<7>
J 0
(3135 685);
DISPLAY 0.659574 (3135 685);
PAINT MONO (3135 685);
DISPLAY INVISIBLE (3135 685);
FORCEPROP 1 LASTPIN (3125 675) BN 7
J 0
(3113 683);
DISPLAY 0.680851 (3113 683);
PAINT GREEN (3113 683);
FORCEPROP 2 LAST CDS_LIB standard
J 0
(3175 675);
PAINT MONO (3175 675);
DISPLAY INVISIBLE (3175 675);
FORCEPROP 1 LAST BODY_TYPE PLUMBING
J 0
(3175 725);
DISPLAY 0.872340 (3175 725);
PAINT GREEN (3175 725);
DISPLAY INVISIBLE (3175 725);
FORCEPROP 1 LAST HDL_TAP TRUE
J 0
(3500 550);
DISPLAY 0.872340 (3500 550);
DISPLAY INVISIBLE (3500 550);
FORCEPROP 1 LAST PATH I94
J 0
(3173 675);
DISPLAY 0.872340 (3173 675);
PAINT GREEN (3173 675);
DISPLAY INVISIBLE (3173 675);
FORCEADD TAP..1
(3175 725);
FORCEPROP 3 LASTPIN (3125 725) SIG_NAME P5E_CPU1_PE3_TX_DP<8>
J 0
(3135 735);
DISPLAY 0.659574 (3135 735);
PAINT MONO (3135 735);
DISPLAY INVISIBLE (3135 735);
FORCEPROP 1 LASTPIN (3125 725) BN 8
J 0
(3113 733);
DISPLAY 0.680851 (3113 733);
PAINT GREEN (3113 733);
FORCEPROP 2 LAST CDS_LIB standard
J 0
(3175 725);
PAINT MONO (3175 725);
DISPLAY INVISIBLE (3175 725);
FORCEPROP 1 LAST BODY_TYPE PLUMBING
J 0
(3175 775);
DISPLAY 0.872340 (3175 775);
PAINT GREEN (3175 775);
DISPLAY INVISIBLE (3175 775);
FORCEPROP 1 LAST HDL_TAP TRUE
J 0
(3500 600);
DISPLAY 0.872340 (3500 600);
DISPLAY INVISIBLE (3500 600);
FORCEPROP 1 LAST PATH I95
J 0
(3173 725);
DISPLAY 0.872340 (3173 725);
PAINT GREEN (3173 725);
DISPLAY INVISIBLE (3173 725);
FORCEADD TAP..1
(3175 775);
FORCEPROP 3 LASTPIN (3125 775) SIG_NAME P5E_CPU1_PE3_TX_DP<9>
J 0
(3135 785);
DISPLAY 0.659574 (3135 785);
PAINT MONO (3135 785);
DISPLAY INVISIBLE (3135 785);
FORCEPROP 1 LASTPIN (3125 775) BN 9
J 0
(3113 783);
DISPLAY 0.680851 (3113 783);
PAINT GREEN (3113 783);
FORCEPROP 2 LAST CDS_LIB standard
J 0
(3175 775);
DISPLAY INVISIBLE (3175 775);
FORCEPROP 1 LAST BODY_TYPE PLUMBING
J 0
(3175 825);
DISPLAY 0.872340 (3175 825);
PAINT GREEN (3175 825);
DISPLAY INVISIBLE (3175 825);
FORCEPROP 1 LAST HDL_TAP TRUE
J 0
(3500 650);
DISPLAY 0.872340 (3500 650);
DISPLAY INVISIBLE (3500 650);
FORCEPROP 1 LAST PATH I96
J 0
(3173 775);
DISPLAY 0.872340 (3173 775);
PAINT GREEN (3173 775);
DISPLAY INVISIBLE (3173 775);
FORCEADD TAP..1
(3175 825);
FORCEPROP 3 LASTPIN (3125 825) SIG_NAME P5E_CPU1_PE3_TX_DP<10>
J 0
(3135 835);
DISPLAY 0.659574 (3135 835);
PAINT MONO (3135 835);
DISPLAY INVISIBLE (3135 835);
FORCEPROP 1 LASTPIN (3125 825) BN 10
J 0
(3113 833);
DISPLAY 0.680851 (3113 833);
PAINT GREEN (3113 833);
FORCEPROP 2 LAST CDS_LIB standard
J 0
(3175 825);
DISPLAY INVISIBLE (3175 825);
FORCEPROP 1 LAST BODY_TYPE PLUMBING
J 0
(3175 875);
DISPLAY 0.872340 (3175 875);
PAINT GREEN (3175 875);
DISPLAY INVISIBLE (3175 875);
FORCEPROP 1 LAST HDL_TAP TRUE
J 0
(3500 700);
DISPLAY 0.872340 (3500 700);
DISPLAY INVISIBLE (3500 700);
FORCEPROP 1 LAST PATH I97
J 0
(3173 825);
DISPLAY 0.872340 (3173 825);
PAINT GREEN (3173 825);
DISPLAY INVISIBLE (3173 825);
FORCEADD TAP..1
(3175 875);
FORCEPROP 3 LASTPIN (3125 875) SIG_NAME P5E_CPU1_PE3_TX_DP<11>
J 0
(3135 885);
DISPLAY 0.659574 (3135 885);
PAINT MONO (3135 885);
DISPLAY INVISIBLE (3135 885);
FORCEPROP 1 LASTPIN (3125 875) BN 11
J 0
(3113 883);
DISPLAY 0.680851 (3113 883);
PAINT GREEN (3113 883);
FORCEPROP 2 LAST CDS_LIB standard
J 0
(3175 875);
DISPLAY INVISIBLE (3175 875);
FORCEPROP 1 LAST BODY_TYPE PLUMBING
J 0
(3175 925);
DISPLAY 0.872340 (3175 925);
PAINT GREEN (3175 925);
DISPLAY INVISIBLE (3175 925);
FORCEPROP 1 LAST HDL_TAP TRUE
J 0
(3500 750);
DISPLAY 0.872340 (3500 750);
DISPLAY INVISIBLE (3500 750);
FORCEPROP 1 LAST PATH I98
J 0
(3173 875);
DISPLAY 0.872340 (3173 875);
PAINT GREEN (3173 875);
DISPLAY INVISIBLE (3173 875);
FORCEADD TAP..1
(3175 975);
FORCEPROP 3 LASTPIN (3125 975) SIG_NAME P5E_CPU1_PE3_TX_DP<13>
J 0
(3135 985);
DISPLAY 0.659574 (3135 985);
PAINT MONO (3135 985);
DISPLAY INVISIBLE (3135 985);
FORCEPROP 1 LASTPIN (3125 975) BN 13
J 0
(3113 983);
DISPLAY 0.680851 (3113 983);
PAINT GREEN (3113 983);
FORCEPROP 2 LAST CDS_LIB standard
J 0
(3175 975);
DISPLAY INVISIBLE (3175 975);
FORCEPROP 1 LAST BODY_TYPE PLUMBING
J 0
(3175 1025);
DISPLAY 0.872340 (3175 1025);
PAINT GREEN (3175 1025);
DISPLAY INVISIBLE (3175 1025);
FORCEPROP 1 LAST HDL_TAP TRUE
J 0
(3500 850);
DISPLAY 0.872340 (3500 850);
DISPLAY INVISIBLE (3500 850);
FORCEPROP 1 LAST PATH I99
J 0
(3173 975);
DISPLAY 0.872340 (3173 975);
PAINT GREEN (3173 975);
DISPLAY INVISIBLE (3173 975);
FORCEADD QUANTA_TITLE_BLOCK_C..1
(6100 -1650);
FORCEPROP 0 LAST CDS_CON_LAST_MODIFIED Fri Aug 25 14:00:43 2023
J 0
(4215 -1635);
PAINT MONO (4215 -1635);
DISPLAY INVISIBLE (4215 -1635);
FORCEPROP 1 LAST CUSTOM_TXT_CDS <CON_LAST_MODIFIED>
J 0
(4215 -1635);
DISPLAY 0.978723 (4215 -1635);
FORCEPROP 2 LAST CUSTOM_TXT_CDS <XR_PAGE_TITLE>
J 0
(-1790 3600);
DISPLAY 0.638298 (-1790 3600);
PAINT PINK (-1790 3600);
DISPLAY INVISIBLE (-1790 3600);
FORCEPROP 2 LAST CUSTOM_TXT_CDS <Q_NUMBER>
J 0
(4697 -1547);
DISPLAY 1.212766 (4697 -1547);
FORCEPROP 1 LAST CUSTOM_TXT_CDS <NAME_2>
J 0
(2925 -1600);
FORCEPROP 1 LAST CUSTOM_TXT_CDS <NAME_1>
J 0
(2925 -1475);
FORCEPROP 1 LAST CUSTOM_TXT_CDS <Q_PROJ>
J 0
(3718 -1548);
DISPLAY 1.212766 (3718 -1548);
FORCEPROP 1 LAST CUSTOM_TXT_CDS <Q_REV>
J 0
(5916 -1547);
DISPLAY 1.212766 (5916 -1547);
FORCEPROP 1 LAST CUSTOM_TXT_CDS <CON_PAGE_NUM> OF <CON_TOTAL_PAGES>
J 0
(5654 -1632);
DISPLAY 0.978723 (5654 -1632);
FORCEPROP 1 LAST Q_TITLE SPR CPU1 - PCIE PE2/PE3 (18 OF 30)
J 0
(-3266 -1624);
DISPLAY 1.957447 (-3266 -1624);
PAINT GREEN (-3266 -1624);
FORCEPROP 1 LAST Q_DEPT 
J 1
(2337 -1601);
DISPLAY 1.957447 (2337 -1601);
PAINT GREEN (2337 -1601);
FORCEPROP 1 LAST COMMENT_BODY TRUE
J 0
(6112 -1663);
DISPLAY 0.978723 (6112 -1663);
PAINT GREEN (6112 -1663);
DISPLAY INVISIBLE (6112 -1663);
FORCEPROP 2 LAST CDS_XR_PAGE_TITLE CR-61 : @S9S_MB_2U_LIB.S9S_MB_2U(SCH_1):PAGE61
J 0
(-1790 3600);
DISPLAY 0.638298 (-1790 3600);
PAINT PINK (-1790 3600);
DISPLAY INVISIBLE (-1790 3600);
FORCEPROP 2 LAST PAGE_BORDER TRUE
J 0
(-1790 3600);
DISPLAY 0.638298 (-1790 3600);
PAINT PINK (-1790 3600);
DISPLAY INVISIBLE (-1790 3600);
FORCEPROP 1 LAST CDS_LMAN_SYM_OUTLINE -9475,6775,100,-125
J 0
(6100 -1650);
DISPLAY 0.468085 (6100 -1650);
PAINT GREEN (6100 -1650);
DISPLAY INVISIBLE (6100 -1650);
FORCEPROP 2 LAST CDS_LIB pure_quanta
J 0
(6100 -1650);
PAINT MONO (6100 -1650);
DISPLAY INVISIBLE (6100 -1650);
WIRE 17 -1 (3225 350)(3225 400);
WIRE 17 -1 (3225 400)(3225 450);
WIRE 17 -1 (3225 450)(3225 500);
WIRE 17 -1 (3225 500)(3225 550);
WIRE 17 -1 (3225 550)(3225 600);
WIRE 17 -1 (3225 600)(3225 650);
WIRE 17 -1 (3225 650)(3225 700);
WIRE 17 -1 (3225 700)(3225 750);
WIRE 17 -1 (3225 750)(3225 800);
WIRE 17 -1 (3225 800)(3225 850);
WIRE 17 -1 (3225 850)(3225 900);
WIRE 17 -1 (3225 900)(3225 950);
WIRE 17 -1 (3225 950)(3225 1000);
WIRE 17 -1 (3225 1000)(3225 1050);
WIRE 17 -1 (3225 1050)(3225 1100);
WIRE 17 -1 (3225 1100)(4225 1100);
FORCEPROP 2 LAST SIG_NAME P5E_CPU1_PE3_TX_DP<15:0>
J 0
(3365 1110);
DISPLAY 0.680851 (3365 1110);
PAINT WHITE (3365 1110);
WIRE 17 -1 (3225 -500)(3225 -450);
WIRE 17 -1 (3225 -450)(3225 -400);
WIRE 17 -1 (3225 -400)(3225 -350);
WIRE 17 -1 (3225 -350)(3225 -300);
WIRE 17 -1 (3225 -300)(3225 -250);
WIRE 17 -1 (3225 -250)(3225 -200);
WIRE 17 -1 (3225 -200)(3225 -150);
WIRE 17 -1 (3225 -150)(3225 -100);
WIRE 17 -1 (3225 -100)(3225 -50);
WIRE 17 -1 (3225 -50)(3225 0);
WIRE 17 -1 (3225 0)(3225 50);
WIRE 17 -1 (3225 50)(3225 100);
WIRE 17 -1 (3225 100)(3225 150);
WIRE 17 -1 (3225 150)(3225 200);
WIRE 17 -1 (3225 200)(3225 250);
WIRE 17 -1 (3225 250)(4225 250);
FORCEPROP 2 LAST SIG_NAME P5E_CPU1_PE3_TX_DN<15:0>
J 0
(3365 260);
DISPLAY 0.680851 (3365 260);
PAINT WHITE (3365 260);
WIRE 17 -1 (-250 350)(-250 400);
WIRE 17 -1 (-250 400)(-250 450);
WIRE 17 -1 (-250 450)(-250 500);
WIRE 17 -1 (-250 500)(-250 550);
WIRE 17 -1 (-250 550)(-250 600);
WIRE 17 -1 (-250 600)(-250 650);
WIRE 17 -1 (-250 650)(-250 700);
WIRE 17 -1 (-250 700)(-250 750);
WIRE 17 -1 (-250 750)(-250 800);
WIRE 17 -1 (-250 800)(-250 850);
WIRE 17 -1 (-250 850)(-250 900);
WIRE 17 -1 (-250 900)(-250 950);
WIRE 17 -1 (-250 950)(-250 1000);
WIRE 17 -1 (-250 1000)(-250 1050);
WIRE 17 -1 (-250 1050)(-250 1100);
WIRE 17 -1 (-1400 1100)(-250 1100);
FORCEPROP 2 LAST SIG_NAME P5E_CPU1_PE3_RX_DP<15:0>
J 0
(-1285 1110);
DISPLAY 0.680851 (-1285 1110);
PAINT WHITE (-1285 1110);
WIRE 17 -1 (-250 -500)(-250 -450);
WIRE 17 -1 (-250 -450)(-250 -400);
WIRE 17 -1 (-250 -400)(-250 -350);
WIRE 17 -1 (-250 -350)(-250 -300);
WIRE 17 -1 (-250 -300)(-250 -250);
WIRE 17 -1 (-250 -250)(-250 -200);
WIRE 17 -1 (-250 -200)(-250 -150);
WIRE 17 -1 (-250 -150)(-250 -100);
WIRE 17 -1 (-250 -100)(-250 -50);
WIRE 17 -1 (-250 -50)(-250 0);
WIRE 17 -1 (-250 0)(-250 50);
WIRE 17 -1 (-250 50)(-250 100);
WIRE 17 -1 (-250 100)(-250 150);
WIRE 17 -1 (-250 150)(-250 200);
WIRE 17 -1 (-250 200)(-250 250);
WIRE 17 -1 (-1400 250)(-250 250);
FORCEPROP 2 LAST SIG_NAME P5E_CPU1_PE3_RX_DN<15:0>
J 0
(-1285 260);
DISPLAY 0.680851 (-1285 260);
PAINT WHITE (-1285 260);
WIRE 17 -1 (3275 3125)(3275 3175);
WIRE 17 -1 (3275 3175)(3275 3225);
WIRE 17 -1 (3275 3225)(3275 3275);
WIRE 17 -1 (3275 3275)(3275 3325);
WIRE 17 -1 (3275 3325)(3275 3375);
WIRE 17 -1 (3275 3375)(3275 3425);
WIRE 17 -1 (3275 3425)(3275 3475);
WIRE 17 -1 (3275 3475)(3275 3525);
WIRE 17 -1 (3275 3525)(3275 3575);
WIRE 17 -1 (3275 3575)(3275 3625);
WIRE 17 -1 (3275 3625)(3275 3675);
WIRE 17 -1 (3275 3675)(3275 3725);
WIRE 17 -1 (3275 3725)(3275 3775);
WIRE 17 -1 (3275 3775)(3275 3825);
WIRE 17 -1 (3275 3825)(3275 3875);
WIRE 17 -1 (3275 3875)(4275 3875);
FORCEPROP 2 LAST SIG_NAME P5E_CPU1_PE2_TX_DP<15:0>
J 0
(3415 3885);
DISPLAY 0.680851 (3415 3885);
PAINT WHITE (3415 3885);
WIRE 17 -1 (3275 2275)(3275 2325);
WIRE 17 -1 (3275 2325)(3275 2375);
WIRE 17 -1 (3275 2375)(3275 2425);
WIRE 17 -1 (3275 2425)(3275 2475);
WIRE 17 -1 (3275 2475)(3275 2525);
WIRE 17 -1 (3275 2525)(3275 2575);
WIRE 17 -1 (3275 2575)(3275 2625);
WIRE 17 -1 (3275 2625)(3275 2675);
WIRE 17 -1 (3275 2675)(3275 2725);
WIRE 17 -1 (3275 2725)(3275 2775);
WIRE 17 -1 (3275 2775)(3275 2825);
WIRE 17 -1 (3275 2825)(3275 2875);
WIRE 17 -1 (3275 2875)(3275 2925);
WIRE 17 -1 (3275 2925)(3275 2975);
WIRE 17 -1 (3275 2975)(3275 3025);
WIRE 17 -1 (3275 3025)(4275 3025);
FORCEPROP 2 LAST SIG_NAME P5E_CPU1_PE2_TX_DN<15:0>
J 0
(3415 3035);
DISPLAY 0.680851 (3415 3035);
PAINT WHITE (3415 3035);
WIRE 17 -1 (-225 3125)(-225 3175);
WIRE 17 -1 (-225 3175)(-225 3225);
WIRE 17 -1 (-225 3225)(-225 3275);
WIRE 17 -1 (-225 3275)(-225 3325);
WIRE 17 -1 (-225 3325)(-225 3375);
WIRE 17 -1 (-225 3375)(-225 3425);
WIRE 17 -1 (-225 3425)(-225 3475);
WIRE 17 -1 (-225 3475)(-225 3525);
WIRE 17 -1 (-225 3525)(-225 3575);
WIRE 17 -1 (-225 3575)(-225 3625);
WIRE 17 -1 (-225 3625)(-225 3675);
WIRE 17 -1 (-225 3675)(-225 3725);
WIRE 17 -1 (-225 3725)(-225 3775);
WIRE 17 -1 (-225 3775)(-225 3825);
WIRE 17 -1 (-225 3825)(-225 3875);
WIRE 17 -1 (-1375 3875)(-225 3875);
FORCEPROP 2 LAST SIG_NAME P5E_CPU1_PE2_RX_DP<15:0>
J 0
(-1260 3885);
DISPLAY 0.680851 (-1260 3885);
PAINT WHITE (-1260 3885);
WIRE 17 -1 (-225 2275)(-225 2325);
WIRE 17 -1 (-225 2325)(-225 2375);
WIRE 17 -1 (-225 2375)(-225 2425);
WIRE 17 -1 (-225 2425)(-225 2475);
WIRE 17 -1 (-225 2475)(-225 2525);
WIRE 17 -1 (-225 2525)(-225 2575);
WIRE 17 -1 (-225 2575)(-225 2625);
WIRE 17 -1 (-225 2625)(-225 2675);
WIRE 17 -1 (-225 2675)(-225 2725);
WIRE 17 -1 (-225 2725)(-225 2775);
WIRE 17 -1 (-225 2775)(-225 2825);
WIRE 17 -1 (-225 2825)(-225 2875);
WIRE 17 -1 (-225 2875)(-225 2925);
WIRE 17 -1 (-225 2925)(-225 2975);
WIRE 17 -1 (-225 2975)(-225 3025);
WIRE 17 -1 (-1375 3025)(-225 3025);
FORCEPROP 2 LAST SIG_NAME P5E_CPU1_PE2_RX_DN<15:0>
J 0
(-1260 3035);
DISPLAY 0.680851 (-1260 3035);
PAINT WHITE (-1260 3035);
WIRE 16 -1 (-125 3000)(300 3000);
WIRE 16 -1 (-125 2950)(300 2950);
WIRE 16 -1 (-125 2900)(300 2900);
WIRE 16 -1 (-125 2850)(300 2850);
WIRE 16 -1 (-125 2800)(300 2800);
WIRE 16 -1 (-125 2750)(300 2750);
WIRE 16 -1 (-125 2700)(300 2700);
WIRE 16 -1 (-125 2650)(300 2650);
WIRE 16 -1 (-125 2600)(300 2600);
WIRE 16 -1 (-125 2550)(300 2550);
WIRE 16 -1 (-125 2500)(300 2500);
WIRE 16 -1 (-125 2450)(300 2450);
WIRE 16 -1 (-125 2400)(300 2400);
WIRE 16 -1 (-125 2350)(300 2350);
WIRE 16 -1 (-125 2300)(300 2300);
WIRE 16 -1 (-125 2250)(300 2250);
WIRE 16 -1 (-125 3850)(300 3850);
WIRE 16 -1 (-125 3800)(300 3800);
WIRE 16 -1 (-125 3750)(300 3750);
WIRE 16 -1 (-125 3700)(300 3700);
WIRE 16 -1 (-125 3650)(300 3650);
WIRE 16 -1 (-125 3600)(300 3600);
WIRE 16 -1 (-125 3550)(300 3550);
WIRE 16 -1 (-125 3500)(300 3500);
WIRE 16 -1 (-125 3450)(300 3450);
WIRE 16 -1 (-125 3400)(300 3400);
WIRE 16 -1 (-125 3350)(300 3350);
WIRE 16 -1 (-125 3300)(300 3300);
WIRE 16 -1 (-125 3250)(300 3250);
WIRE 16 -1 (-125 3200)(300 3200);
WIRE 16 -1 (-125 3150)(300 3150);
WIRE 16 -1 (-125 3100)(300 3100);
WIRE 16 -1 (2700 3000)(3175 3000);
WIRE 16 -1 (2700 2950)(3175 2950);
WIRE 16 -1 (2700 2900)(3175 2900);
WIRE 16 -1 (2700 2850)(3175 2850);
WIRE 16 -1 (2700 2800)(3175 2800);
WIRE 16 -1 (2700 2750)(3175 2750);
WIRE 16 -1 (2700 2700)(3175 2700);
WIRE 16 -1 (2700 2650)(3175 2650);
WIRE 16 -1 (2700 2600)(3175 2600);
WIRE 16 -1 (2700 2550)(3175 2550);
WIRE 16 -1 (2700 2500)(3175 2500);
WIRE 16 -1 (2700 2450)(3175 2450);
WIRE 16 -1 (2700 2400)(3175 2400);
WIRE 16 -1 (2700 2350)(3175 2350);
WIRE 16 -1 (2700 2300)(3175 2300);
WIRE 16 -1 (2700 2250)(3175 2250);
WIRE 16 -1 (2700 3850)(3175 3850);
WIRE 16 -1 (2700 3800)(3175 3800);
WIRE 16 -1 (2700 3750)(3175 3750);
WIRE 16 -1 (2700 3700)(3175 3700);
WIRE 16 -1 (2700 3650)(3175 3650);
WIRE 16 -1 (2700 3600)(3175 3600);
WIRE 16 -1 (2700 3550)(3175 3550);
WIRE 16 -1 (2700 3500)(3175 3500);
WIRE 16 -1 (2700 3450)(3175 3450);
WIRE 16 -1 (2700 3400)(3175 3400);
WIRE 16 -1 (2700 3350)(3175 3350);
WIRE 16 -1 (2700 3300)(3175 3300);
WIRE 16 -1 (2700 3250)(3175 3250);
WIRE 16 -1 (2700 3200)(3175 3200);
WIRE 16 -1 (2700 3150)(3175 3150);
WIRE 16 -1 (2700 3100)(3175 3100);
WIRE 16 -1 (-150 225)(300 225);
WIRE 16 -1 (-150 175)(300 175);
WIRE 16 -1 (-150 125)(300 125);
WIRE 16 -1 (-150 75)(300 75);
WIRE 16 -1 (-150 25)(300 25);
WIRE 16 -1 (-150 -25)(300 -25);
WIRE 16 -1 (-150 -75)(300 -75);
WIRE 16 -1 (-150 -125)(300 -125);
WIRE 16 -1 (-150 -175)(300 -175);
WIRE 16 -1 (-150 -225)(300 -225);
WIRE 16 -1 (-150 -275)(300 -275);
WIRE 16 -1 (-150 -325)(300 -325);
WIRE 16 -1 (-150 -375)(300 -375);
WIRE 16 -1 (-150 -425)(300 -425);
WIRE 16 -1 (-150 -475)(300 -475);
WIRE 16 -1 (-150 -525)(300 -525);
WIRE 16 -1 (-150 1075)(300 1075);
WIRE 16 -1 (-150 1025)(300 1025);
WIRE 16 -1 (-150 975)(300 975);
WIRE 16 -1 (-150 925)(300 925);
WIRE 16 -1 (-150 875)(300 875);
WIRE 16 -1 (-150 825)(300 825);
WIRE 16 -1 (-150 775)(300 775);
WIRE 16 -1 (-150 725)(300 725);
WIRE 16 -1 (-150 675)(300 675);
WIRE 16 -1 (-150 625)(300 625);
WIRE 16 -1 (-150 575)(300 575);
WIRE 16 -1 (-150 525)(300 525);
WIRE 16 -1 (-150 475)(300 475);
WIRE 16 -1 (-150 425)(300 425);
WIRE 16 -1 (-150 375)(300 375);
WIRE 16 -1 (-150 325)(300 325);
WIRE 16 -1 (2700 225)(3125 225);
WIRE 16 -1 (2700 175)(3125 175);
WIRE 16 -1 (2700 125)(3125 125);
WIRE 16 -1 (2700 75)(3125 75);
WIRE 16 -1 (2700 25)(3125 25);
WIRE 16 -1 (2700 -25)(3125 -25);
WIRE 16 -1 (2700 -75)(3125 -75);
WIRE 16 -1 (2700 -125)(3125 -125);
WIRE 16 -1 (2700 -175)(3125 -175);
WIRE 16 -1 (2700 -225)(3125 -225);
WIRE 16 -1 (2700 -275)(3125 -275);
WIRE 16 -1 (2700 -325)(3125 -325);
WIRE 16 -1 (2700 -375)(3125 -375);
WIRE 16 -1 (2700 -425)(3125 -425);
WIRE 16 -1 (2700 -475)(3125 -475);
WIRE 16 -1 (2700 -525)(3125 -525);
WIRE 16 -1 (2700 1075)(3125 1075);
WIRE 16 -1 (2700 1025)(3125 1025);
WIRE 16 -1 (2700 975)(3125 975);
WIRE 16 -1 (2700 925)(3125 925);
WIRE 16 -1 (2700 875)(3125 875);
WIRE 16 -1 (2700 825)(3125 825);
WIRE 16 -1 (2700 775)(3125 775);
WIRE 16 -1 (2700 725)(3125 725);
WIRE 16 -1 (2700 675)(3125 675);
WIRE 16 -1 (2700 625)(3125 625);
WIRE 16 -1 (2700 575)(3125 575);
WIRE 16 -1 (2700 525)(3125 525);
WIRE 16 -1 (2700 475)(3125 475);
WIRE 16 -1 (2700 425)(3125 425);
WIRE 16 -1 (2700 375)(3125 375);
WIRE 16 -1 (2700 325)(3125 325);
FORCENOTE
20210818 MODIFY FOR GT
(-25 4600) 0;
DISPLAY LEFT (-25 4600);
DISPLAY 2.510638 (-25 4600);
PAINT PINK (-25 4600);
QUIT
